(kicad_pcb
	(version 20260206)
	(generator "pcbnew")
	(generator_version "10.0")
	(general
		(thickness 1.59074)
		(legacy_teardrops no)
	)
	(paper "A4")
	(layers
		(0 "F.Cu" signal "L01-Top Layer")
		(4 "In1.Cu" signal "L02-Inner Layer")
		(6 "In2.Cu" signal "L03-Inner Layer")
		(2 "B.Cu" signal "L04-Bottom Layer")
		(9 "F.Adhes" user "F.Adhesive")
		(11 "B.Adhes" user "B.Adhesive")
		(13 "F.Paste" user "Top Paste")
		(15 "B.Paste" user "Bottom Paste")
		(5 "F.SilkS" user "Top Overlay")
		(7 "B.SilkS" user "Bottom Overlay")
		(1 "F.Mask" user "Top Solder")
		(3 "B.Mask" user "Bottom Solder")
		(17 "Dwgs.User" user "User.Drawings")
		(19 "Cmts.User" user "User.Comments")
		(21 "Eco1.User" user "User.Eco1")
		(23 "Eco2.User" user "User.Eco2")
		(25 "Edge.Cuts" user)
		(27 "Margin" user)
		(31 "F.CrtYd" user "Top Courtyard")
		(29 "B.CrtYd" user "Bottom Courtyard")
		(35 "F.Fab" user "Top Component Outline")
		(33 "B.Fab" user "Bottom Component Outline 2")
	)
	(setup
		(pad_to_mask_clearance 0.05)
		(allow_soldermask_bridges_in_footprints no)
		(tenting
			(front yes)
			(back yes)
		)
		(covering
			(front no)
			(back no)
		)
		(plugging
			(front no)
			(back no)
		)
		(capping no)
		(filling no)
		(aux_axis_origin -1.574895 280.103605)
		(grid_origin -1.574895 280.103605)
		(pcbplotparams
			(layerselection 0x00000000_00000000_55555555_5755f5ff)
			(plot_on_all_layers_selection 0x00000000_00000000_00000000_00000000)
			(disableapertmacros no)
			(usegerberextensions no)
			(usegerberattributes yes)
			(usegerberadvancedattributes yes)
			(creategerberjobfile yes)
			(dashed_line_dash_ratio 12)
			(dashed_line_gap_ratio 3)
			(svgprecision 4)
			(plotframeref no)
			(mode 1)
			(useauxorigin no)
			(pdf_front_fp_property_popups yes)
			(pdf_back_fp_property_popups yes)
			(pdf_metadata yes)
			(pdf_single_document no)
			(dxfpolygonmode yes)
			(dxfimperialunits yes)
			(dxfusepcbnewfont yes)
			(psnegative no)
			(psa4output no)
			(plot_black_and_white yes)
			(sketchpadsonfab no)
			(plotpadnumbers no)
			(hidednponfab no)
			(sketchdnponfab yes)
			(crossoutdnponfab yes)
			(subtractmaskfromsilk no)
			(outputformat 1)
			(mirror no)
			(drillshape 1)
			(scaleselection 1)
			(outputdirectory "")
		)
	)
	(footprint "FAB_SA45_DaughterCard:Microchip_SA45"
		(locked yes)
		(layer "F.Cu")
		(at 149.501105 105.003605 180)
		(property "Reference" "U1"
			(at 21.025 16.58071 0)
			(unlocked yes)
			(layer "F.SilkS")
			(effects
				(font
					(face "Arial")
					(size 0.63 0.63)
					(thickness 0.254)
				)
			)
		)
		(property "Value" "Microchip_SA45"
			(at 7.280385 -22.215602 0)
			(unlocked yes)
			(layer "F.SilkS")
			(hide yes)
			(effects
				(font
					(size 1.524 1.524)
					(thickness 0.254)
				)
			)
		)
		(sheetname "SCH_SA45_DaughterCard")
		(sheetfile "SCH_SA45_DaughterCard.kicad_sch")
		(duplicate_pad_numbers_are_jumpers no)
		(fp_line
			(start 20.6 17.9)
			(end -20.6 17.9)
			(stroke
				(width 0.1)
				(type solid)
			)
			(layer "F.CrtYd")
		)
		(fp_line
			(start 20.6 -17.9)
			(end 20.6 17.9)
			(stroke
				(width 0.1)
				(type solid)
			)
			(layer "F.CrtYd")
		)
		(fp_line
			(start 20.6 -17.9)
			(end -20.6 -17.9)
			(stroke
				(width 0.1)
				(type solid)
			)
			(layer "F.CrtYd")
		)
		(fp_line
			(start -20.6 -17.9)
			(end -20.6 17.9)
			(stroke
				(width 0.1)
				(type solid)
			)
			(layer "F.CrtYd")
		)
		(fp_text user ""
			(at 1.117795 -0.44646 180)
			(unlocked yes)
			(layer "F.Fab")
			(effects
				(font
					(face "Arial")
					(size 0.63 0.63)
					(thickness 0.254)
				)
			)
		)
		(fp_text user "${REFERENCE}"
			(at -0.0127 -0.11801 180)
			(unlocked yes)
			(layer "F.Fab")
			(effects
				(font
					(face "Arial")
					(size 0.63 0.63)
					(thickness 0.254)
				)
			)
		)
		(pad "1" thru_hole circle
			(at 16.51 12.7 270)
			(size 1.524 1.524)
			(drill 0.762)
			(layers "*.Cu" "*.Mask")
			(remove_unused_layers no)
			(thermal_bridge_angle 90)
		)
		(pad "4" thru_hole circle
			(at 16.51 -2.54 270)
			(size 1.524 1.524)
			(drill 0.762)
			(layers "*.Cu" "*.Mask")
			(remove_unused_layers no)
			(thermal_bridge_angle 90)
		)
		(pad "5" thru_hole circle
			(at 16.51 -7.62 270)
			(size 1.524 1.524)
			(drill 0.762)
			(layers "*.Cu" "*.Mask")
			(remove_unused_layers no)
			(net "TX")
			(thermal_bridge_angle 90)
		)
		(pad "6" thru_hole circle
			(at 16.51 -12.7 270)
			(size 1.524 1.524)
			(drill 0.762)
			(layers "*.Cu" "*.Mask")
			(remove_unused_layers no)
			(net "RX")
			(thermal_bridge_angle 90)
		)
		(pad "7" thru_hole circle
			(at -16.51 -12.7 270)
			(size 1.562 1.562)
			(drill 0.962)
			(layers "*.Cu" "*.Mask")
			(remove_unused_layers no)
			(net "+3.3V_OSC")
			(thermal_bridge_angle 90)
		)
		(pad "8" thru_hole circle
			(at -16.51 -7.62 270)
			(size 1.562 1.562)
			(drill 0.962)
			(layers "*.Cu" "*.Mask")
			(remove_unused_layers no)
			(net "GND")
			(thermal_bridge_angle 90)
		)
		(pad "9" thru_hole circle
			(at -16.51 -2.54 270)
			(size 1.562 1.562)
			(drill 0.962)
			(layers "*.Cu" "*.Mask")
			(remove_unused_layers no)
			(net "1PPS_IN")
			(thermal_bridge_angle 90)
		)
		(pad "10" thru_hole circle
			(at -16.51 2.54 270)
			(size 1.562 1.562)
			(drill 0.962)
			(layers "*.Cu" "*.Mask")
			(remove_unused_layers no)
			(net "1PPS_OUT")
			(thermal_bridge_angle 90)
		)
		(pad "12" thru_hole circle
			(at -16.51 12.7 180)
			(size 1.562 1.562)
			(drill 0.962)
			(layers "*.Cu" "*.Mask")
			(remove_unused_layers no)
			(net "RF_OUTPUT")
			(thermal_bridge_angle 90)
		)
	)
	(footprint "Vault:FID_1p0mm"
		(layer "F.Cu")
		(at 171.286105 81.818605)
		(property "Reference" "Designator3"
			(at 7.084135 -3.019298 0)
			(unlocked yes)
			(layer "F.SilkS")
			(hide yes)
			(effects
				(font
					(size 1.524 1.524)
					(thickness 0.254)
				)
			)
		)
		(property "Value" "Comment"
			(at 5.07844 -0.707898 0)
			(unlocked yes)
			(layer "F.SilkS")
			(hide yes)
			(effects
				(font
					(size 1.524 1.524)
					(thickness 0.254)
				)
			)
		)
		(sheetfile ".kicad_sch")
		(duplicate_pad_numbers_are_jumpers no)
		(fp_circle
			(center 0 0)
			(end 0 -1)
			(stroke
				(width 0.1)
				(type solid)
			)
			(fill no)
			(layer "F.CrtYd")
		)
		(pad "1" smd circle
			(at 0 0 90)
			(size 1 1)
			(layers "F.Cu" "F.Mask" "F.Paste")
			(solder_mask_margin 0.5)
			(solder_paste_margin -6)
			(thermal_bridge_angle 90)
		)
		(zone
			(layer "F.Cu")
			(hatch edge 0.5)
			(connect_pads
				(clearance 0)
			)
			(min_thickness 0.25)
			(keepout
				(tracks not_allowed)
				(vias not_allowed)
				(pads allowed)
				(copperpour not_allowed)
				(footprints allowed)
			)
			(placement
				(enabled no)
				(sheetname "")
			)
			(fill
				(thermal_gap 0.5)
				(thermal_bridge_width 0.5)
				(island_removal_mode 0)
			)
			(polygon
				(pts
					(xy 171.57639 80.861665) (xy 171.757502 80.936684) (xy 171.920498 81.045595) (xy 172.059115 81.184212)
					(xy 172.168026 81.347208) (xy 172.243045 81.52832) (xy 172.28129 81.720588) (xy 172.28129 81.916622)
					(xy 172.243045 82.10889) (xy 172.168026 82.290002) (xy 172.059115 82.452998) (xy 171.920498 82.591615)
					(xy 171.757502 82.700526) (xy 171.57639 82.775545) (xy 171.384122 82.81379) (xy 171.188088 82.81379)
					(xy 170.99582 82.775545) (xy 170.814708 82.700526) (xy 170.651712 82.591615) (xy 170.513095 82.452998)
					(xy 170.404184 82.290002) (xy 170.329165 82.10889) (xy 170.29092 81.916622) (xy 170.29092 81.752779)
					(xy 170.786105 81.752779) (xy 170.786105 81.884431) (xy 170.82018 82.011598) (xy 170.886006 82.125612)
					(xy 170.979098 82.218704) (xy 171.093112 82.28453) (xy 171.220279 82.318605) (xy 171.351931 82.318605)
					(xy 171.479098 82.28453) (xy 171.593112 82.218704) (xy 171.686204 82.125612) (xy 171.75203 82.011598)
					(xy 171.786105 81.884431) (xy 171.786105 81.752779) (xy 171.75203 81.625612) (xy 171.686204 81.511598)
					(xy 171.593112 81.418506) (xy 171.479098 81.35268) (xy 171.351931 81.318605) (xy 171.220279 81.318605)
					(xy 171.093112 81.35268) (xy 170.979098 81.418506) (xy 170.886006 81.511598) (xy 170.82018 81.625612)
					(xy 170.786105 81.752779) (xy 170.29092 81.752779) (xy 170.29092 81.720588) (xy 170.329165 81.52832)
					(xy 170.404184 81.347208) (xy 170.513095 81.184212) (xy 170.651712 81.045595) (xy 170.814708 80.936684)
					(xy 170.99582 80.861665) (xy 171.188088 80.82342) (xy 171.384122 80.82342)
				)
			)
		)
	)
	(footprint "Vault:FID_1p0mm"
		(layer "F.Cu")
		(at 125.786105 81.818605)
		(property "Reference" "Designator1"
			(at 7.084135 -3.019298 0)
			(unlocked yes)
			(layer "F.SilkS")
			(hide yes)
			(effects
				(font
					(size 1.524 1.524)
					(thickness 0.254)
				)
			)
		)
		(property "Value" "Comment"
			(at 5.07844 -0.707898 0)
			(unlocked yes)
			(layer "F.SilkS")
			(hide yes)
			(effects
				(font
					(size 1.524 1.524)
					(thickness 0.254)
				)
			)
		)
		(sheetfile ".kicad_sch")
		(duplicate_pad_numbers_are_jumpers no)
		(fp_circle
			(center 0 0)
			(end 0 -1)
			(stroke
				(width 0.1)
				(type solid)
			)
			(fill no)
			(layer "F.CrtYd")
		)
		(pad "1" smd circle
			(at 0 0 90)
			(size 1 1)
			(layers "F.Cu" "F.Mask" "F.Paste")
			(solder_mask_margin 0.5)
			(solder_paste_margin -6)
			(thermal_bridge_angle 90)
		)
		(zone
			(layer "F.Cu")
			(hatch edge 0.5)
			(connect_pads
				(clearance 0)
			)
			(min_thickness 0.25)
			(keepout
				(tracks not_allowed)
				(vias not_allowed)
				(pads allowed)
				(copperpour not_allowed)
				(footprints allowed)
			)
			(placement
				(enabled no)
				(sheetname "")
			)
			(fill
				(thermal_gap 0.5)
				(thermal_bridge_width 0.5)
				(island_removal_mode 0)
			)
			(polygon
				(pts
					(xy 126.07639 80.861665) (xy 126.257502 80.936684) (xy 126.420498 81.045595) (xy 126.559115 81.184212)
					(xy 126.668026 81.347208) (xy 126.743045 81.52832) (xy 126.78129 81.720588) (xy 126.78129 81.916622)
					(xy 126.743045 82.10889) (xy 126.668026 82.290002) (xy 126.559115 82.452998) (xy 126.420498 82.591615)
					(xy 126.257502 82.700526) (xy 126.07639 82.775545) (xy 125.884122 82.81379) (xy 125.688088 82.81379)
					(xy 125.49582 82.775545) (xy 125.314708 82.700526) (xy 125.151712 82.591615) (xy 125.013095 82.452998)
					(xy 124.904184 82.290002) (xy 124.829165 82.10889) (xy 124.79092 81.916622) (xy 124.79092 81.752779)
					(xy 125.286105 81.752779) (xy 125.286105 81.884431) (xy 125.32018 82.011598) (xy 125.386006 82.125612)
					(xy 125.479098 82.218704) (xy 125.593112 82.28453) (xy 125.720279 82.318605) (xy 125.851931 82.318605)
					(xy 125.979098 82.28453) (xy 126.093112 82.218704) (xy 126.186204 82.125612) (xy 126.25203 82.011598)
					(xy 126.286105 81.884431) (xy 126.286105 81.752779) (xy 126.25203 81.625612) (xy 126.186204 81.511598)
					(xy 126.093112 81.418506) (xy 125.979098 81.35268) (xy 125.851931 81.318605) (xy 125.720279 81.318605)
					(xy 125.593112 81.35268) (xy 125.479098 81.418506) (xy 125.386006 81.511598) (xy 125.32018 81.625612)
					(xy 125.286105 81.752779) (xy 124.79092 81.752779) (xy 124.79092 81.720588) (xy 124.829165 81.52832)
					(xy 124.904184 81.347208) (xy 125.013095 81.184212) (xy 125.151712 81.045595) (xy 125.314708 80.936684)
					(xy 125.49582 80.861665) (xy 125.688088 80.82342) (xy 125.884122 80.82342)
				)
			)
		)
	)
	(footprint "FAB_SA45_DaughterCard:IQD_ICPT-1"
		(locked yes)
		(layer "F.Cu")
		(at 149.501105 105.003605 180)
		(property "Reference" "U2"
			(at 23.35 17.75571 0)
			(unlocked yes)
			(layer "F.SilkS")
			(effects
				(font
					(face "Arial")
					(size 0.63 0.63)
					(thickness 0.254)
				)
			)
		)
		(property "Value" "IQD_ICPT-1"
			(at 43.90612 -29.403802 0)
			(unlocked yes)
			(layer "F.SilkS")
			(hide yes)
			(effects
				(font
					(size 1.524 1.524)
					(thickness 0.254)
				)
			)
		)
		(sheetname "SCH_SA45_DaughterCard")
		(sheetfile "SCH_SA45_DaughterCard.kicad_sch")
		(duplicate_pad_numbers_are_jumpers no)
		(fp_line
			(start 22.7 18.2)
			(end -22.7 18.2)
			(stroke
				(width 0.1)
				(type solid)
			)
			(layer "F.CrtYd")
		)
		(fp_line
			(start 22.7 -18.2)
			(end 22.7 18.2)
			(stroke
				(width 0.1)
				(type solid)
			)
			(layer "F.CrtYd")
		)
		(fp_line
			(start 22.7 -18.2)
			(end -11.8 -18.2)
			(stroke
				(width 0.1)
				(type solid)
			)
			(layer "F.CrtYd")
		)
		(fp_line
			(start -11.8 -18.2)
			(end -22.7 -18.2)
			(stroke
				(width 0.1)
				(type solid)
			)
			(layer "F.CrtYd")
		)
		(fp_line
			(start -22.7 -18.2)
			(end -22.7 18.2)
			(stroke
				(width 0.1)
				(type solid)
			)
			(layer "F.CrtYd")
		)
		(fp_text user ""
			(at 1.117795 -0.44646 180)
			(unlocked yes)
			(layer "F.Fab")
			(effects
				(font
					(face "Arial")
					(size 0.63 0.63)
					(thickness 0.254)
				)
			)
		)
		(fp_text user "${REFERENCE}"
			(at -0.0127 -0.11801 180)
			(unlocked yes)
			(layer "F.Fab")
			(effects
				(font
					(face "Arial")
					(size 0.63 0.63)
					(thickness 0.254)
				)
			)
		)
		(pad "1" thru_hole circle
			(at 16.51 12.7 270)
			(size 1.8 1.8)
			(drill 1.2)
			(layers "*.Cu" "*.Mask")
			(remove_unused_layers no)
			(thermal_bridge_angle 90)
		)
		(pad "2" thru_hole circle
			(at 16.51 -2.54 270)
			(size 1.8 1.8)
			(drill 1.2)
			(layers "*.Cu" "*.Mask")
			(remove_unused_layers no)
			(thermal_bridge_angle 90)
		)
		(pad "3" thru_hole circle
			(at 16.51 -7.62 270)
			(size 1.8 1.8)
			(drill 1.2)
			(layers "*.Cu" "*.Mask")
			(remove_unused_layers no)
			(net "TX")
			(thermal_bridge_angle 90)
		)
		(pad "4" thru_hole circle
			(at 16.51 -12.7 270)
			(size 1.8 1.8)
			(drill 1.2)
			(layers "*.Cu" "*.Mask")
			(remove_unused_layers no)
			(net "RX")
			(thermal_bridge_angle 90)
		)
		(pad "5" thru_hole circle
			(at -16.51 -12.7 270)
			(size 1.8 1.8)
			(drill 1.2)
			(layers "*.Cu" "*.Mask")
			(remove_unused_layers no)
			(net "+3.3V_OSC")
			(thermal_bridge_angle 90)
		)
		(pad "6" thru_hole circle
			(at -16.51 -7.62 270)
			(size 1.8 1.8)
			(drill 1.2)
			(layers "*.Cu" "*.Mask")
			(remove_unused_layers no)
			(net "GND")
			(thermal_bridge_angle 90)
		)
		(pad "7" thru_hole circle
			(at -16.51 -2.54 270)
			(size 1.8 1.8)
			(drill 1.2)
			(layers "*.Cu" "*.Mask")
			(remove_unused_layers no)
			(net "1PPS_IN")
			(thermal_bridge_angle 90)
		)
		(pad "8" thru_hole circle
			(at -16.51 2.54 270)
			(size 1.8 1.8)
			(drill 1.2)
			(layers "*.Cu" "*.Mask")
			(remove_unused_layers no)
			(net "1PPS_OUT")
			(thermal_bridge_angle 90)
		)
		(pad "9" thru_hole circle
			(at -16.51 12.7 180)
			(size 1.8 1.8)
			(drill 1.2)
			(layers "*.Cu" "*.Mask")
			(remove_unused_layers no)
			(net "RF_OUTPUT")
			(thermal_bridge_angle 90)
		)
		(zone
			(layer "F.Cu")
			(hatch edge 0.5)
			(connect_pads
				(clearance 0)
			)
			(min_thickness 0.25)
			(keepout
				(tracks not_allowed)
				(vias not_allowed)
				(pads not_allowed)
				(copperpour not_allowed)
				(footprints allowed)
			)
			(placement
				(enabled no)
				(sheetname "")
			)
			(fill
				(thermal_gap 0.5)
				(thermal_bridge_width 0.5)
				(island_removal_mode 0)
			)
			(polygon
				(pts
					(xy 172.001105 123.003605) (xy 172.001105 87.003605) (xy 127.001105 87.003605) (xy 127.001105 123.003605)
				)
			)
		)
	)
	(footprint "Vault:FID_1p0mm"
		(layer "F.Cu")
		(at 125.961105 128.043605)
		(property "Reference" "Designator2"
			(at 7.084135 -3.019298 0)
			(unlocked yes)
			(layer "F.SilkS")
			(hide yes)
			(effects
				(font
					(size 1.524 1.524)
					(thickness 0.254)
				)
			)
		)
		(property "Value" "Comment"
			(at 5.07844 -0.707898 0)
			(unlocked yes)
			(layer "F.SilkS")
			(hide yes)
			(effects
				(font
					(size 1.524 1.524)
					(thickness 0.254)
				)
			)
		)
		(sheetfile ".kicad_sch")
		(duplicate_pad_numbers_are_jumpers no)
		(fp_circle
			(center 0 0)
			(end 0 -1)
			(stroke
				(width 0.1)
				(type solid)
			)
			(fill no)
			(layer "F.CrtYd")
		)
		(pad "1" smd circle
			(at 0 0 90)
			(size 1 1)
			(layers "F.Cu" "F.Mask" "F.Paste")
			(solder_mask_margin 0.5)
			(solder_paste_margin -6)
			(thermal_bridge_angle 90)
		)
		(zone
			(layer "F.Cu")
			(hatch edge 0.5)
			(connect_pads
				(clearance 0)
			)
			(min_thickness 0.25)
			(keepout
				(tracks not_allowed)
				(vias not_allowed)
				(pads allowed)
				(copperpour not_allowed)
				(footprints allowed)
			)
			(placement
				(enabled no)
				(sheetname "")
			)
			(fill
				(thermal_gap 0.5)
				(thermal_bridge_width 0.5)
				(island_removal_mode 0)
			)
			(polygon
				(pts
					(xy 126.25139 127.086665) (xy 126.432502 127.161684) (xy 126.595498 127.270595) (xy 126.734115 127.409212)
					(xy 126.843026 127.572208) (xy 126.918045 127.75332) (xy 126.95629 127.945588) (xy 126.95629 128.141622)
					(xy 126.918045 128.33389) (xy 126.843026 128.515002) (xy 126.734115 128.677998) (xy 126.595498 128.816615)
					(xy 126.432502 128.925526) (xy 126.25139 129.000545) (xy 126.059122 129.03879) (xy 125.863088 129.03879)
					(xy 125.67082 129.000545) (xy 125.489708 128.925526) (xy 125.326712 128.816615) (xy 125.188095 128.677998)
					(xy 125.079184 128.515002) (xy 125.004165 128.33389) (xy 124.96592 128.141622) (xy 124.96592 127.977779)
					(xy 125.461105 127.977779) (xy 125.461105 128.109431) (xy 125.49518 128.236598) (xy 125.561006 128.350612)
					(xy 125.654098 128.443704) (xy 125.768112 128.50953) (xy 125.895279 128.543605) (xy 126.026931 128.543605)
					(xy 126.154098 128.50953) (xy 126.268112 128.443704) (xy 126.361204 128.350612) (xy 126.42703 128.236598)
					(xy 126.461105 128.109431) (xy 126.461105 127.977779) (xy 126.42703 127.850612) (xy 126.361204 127.736598)
					(xy 126.268112 127.643506) (xy 126.154098 127.57768) (xy 126.026931 127.543605) (xy 125.895279 127.543605)
					(xy 125.768112 127.57768) (xy 125.654098 127.643506) (xy 125.561006 127.736598) (xy 125.49518 127.850612)
					(xy 125.461105 127.977779) (xy 124.96592 127.977779) (xy 124.96592 127.945588) (xy 125.004165 127.75332)
					(xy 125.079184 127.572208) (xy 125.188095 127.409212) (xy 125.326712 127.270595) (xy 125.489708 127.161684)
					(xy 125.67082 127.086665) (xy 125.863088 127.04842) (xy 126.059122 127.04842)
				)
			)
		)
	)
	(footprint "Vault:TH001V_109DIA_000mt_8600-0"
		(layer "B.Cu")
		(at 142.431105 81.993605 180)
		(property "Reference" "P10"
			(at 0 -1.90429 0)
			(unlocked yes)
			(layer "B.SilkS")
			(effects
				(font
					(face "Arial")
					(size 0.63 0.63)
					(thickness 0.254)
				)
				(justify mirror)
			)
		)
		(property "Value" "Mill-Max_8600-0-05-80-00-00-03-0"
			(at 22.534825 -2.89778 0)
			(unlocked yes)
			(layer "B.SilkS")
			(hide yes)
			(effects
				(font
					(face "Arial")
					(size 0.63 0.63)
					(thickness 0.254)
				)
				(justify mirror)
			)
		)
		(sheetname "SCH_SA45_DaughterCard")
		(sheetfile "SCH_SA45_DaughterCard.kicad_sch")
		(duplicate_pad_numbers_are_jumpers no)
		(fp_line
			(start 1.4 1.4)
			(end -1.4 1.4)
			(stroke
				(width 0.1)
				(type solid)
			)
			(layer "B.CrtYd")
		)
		(fp_line
			(start 1.4 -1.4)
			(end 1.4 1.4)
			(stroke
				(width 0.1)
				(type solid)
			)
			(layer "B.CrtYd")
		)
		(fp_line
			(start 1.4 -1.4)
			(end -1.4 -1.4)
			(stroke
				(width 0.1)
				(type solid)
			)
			(layer "B.CrtYd")
		)
		(fp_line
			(start -1.4 -1.4)
			(end -1.4 1.4)
			(stroke
				(width 0.1)
				(type solid)
			)
			(layer "B.CrtYd")
		)
		(fp_circle
			(center 0 0)
			(end 0 0.545)
			(stroke
				(width 0.1)
				(type solid)
			)
			(fill no)
			(layer "B.Fab")
		)
		(fp_text user "${REFERENCE}"
			(at 0.000005 0.166251 360)
			(unlocked yes)
			(layer "B.Fab")
			(effects
				(font
					(face "Arial")
					(size 0.8001 0.8001)
					(thickness 0.254)
				)
				(justify mirror)
			)
		)
		(pad "1" thru_hole circle
			(at 0 -0.02 180)
			(size 2.09 2.09)
			(drill 1.09)
			(layers "*.Cu" "*.Mask")
			(remove_unused_layers no)
			(net "1PPS_OUT")
			(solder_mask_margin 0.05)
			(solder_paste_margin -2147.48364)
			(thermal_bridge_angle 90)
		)
	)
	(footprint "Vault:CAPC0603X033N"
		(layer "B.Cu")
		(at 143.026105 104.798605 -90)
		(property "Reference" "C4"
			(at -3.4161 0.48 0)
			(unlocked yes)
			(layer "B.SilkS")
			(effects
				(font
					(face "Arial")
					(size 0.63 0.63)
					(thickness 0.254)
				)
				(justify mirror)
			)
		)
		(property "Value" "Murata_GRM0335C1E330JA01D"
			(at 11.84658 -8.56076 0)
			(unlocked yes)
			(layer "B.SilkS")
			(hide yes)
			(effects
				(font
					(face "Arial")
					(size 0.63 0.63)
					(thickness 0.254)
				)
				(justify mirror)
			)
		)
		(sheetname "SCH_SA45_DaughterCard")
		(sheetfile "SCH_SA45_DaughterCard.kicad_sch")
		(duplicate_pad_numbers_are_jumpers no)
		(fp_line
			(start -0.75 0.4)
			(end -0.75 -0.4)
			(stroke
				(width 0.1)
				(type solid)
			)
			(layer "B.CrtYd")
		)
		(fp_line
			(start 0.75 0.4)
			(end -0.75 0.4)
			(stroke
				(width 0.1)
				(type solid)
			)
			(layer "B.CrtYd")
		)
		(fp_line
			(start 0.75 0.4)
			(end 0.75 -0.4)
			(stroke
				(width 0.1)
				(type solid)
			)
			(layer "B.CrtYd")
		)
		(fp_line
			(start 0.75 -0.4)
			(end -0.75 -0.4)
			(stroke
				(width 0.1)
				(type solid)
			)
			(layer "B.CrtYd")
		)
		(fp_line
			(start -0.3 0.15)
			(end -0.3 -0.15)
			(stroke
				(width 0.05)
				(type solid)
			)
			(layer "B.Fab")
		)
		(fp_line
			(start 0.3 0.15)
			(end -0.3 0.15)
			(stroke
				(width 0.05)
				(type solid)
			)
			(layer "B.Fab")
		)
		(fp_line
			(start 0.3 0.15)
			(end 0.3 -0.15)
			(stroke
				(width 0.05)
				(type solid)
			)
			(layer "B.Fab")
		)
		(fp_line
			(start 0.3 -0.15)
			(end -0.3 -0.15)
			(stroke
				(width 0.05)
				(type solid)
			)
			(layer "B.Fab")
		)
		(fp_text_box "${REFERENCE}"
			(start -0.20757 1.14715)
			(end 0.20756 -1.14715)
			(margins 0 0 0 0)
			(angle 90)
			(layer "B.Fab")
			(effects
				(font
					(face "Arial")
					(size 0.315 0.315)
					(thickness 0.254)
				)
				(justify top mirror)
			)
			(border no)
			(stroke
				(width 0.1)
				(type default)
			)
			(knockout no)
		)
		(pad "1" smd rect
			(at -0.33 0 270)
			(size 0.46 0.42)
			(layers "B.Cu" "B.Mask" "B.Paste")
			(net "+3.3V")
			(solder_mask_margin 0.05)
			(solder_paste_margin 0)
		)
		(pad "2" smd rect
			(at 0.33 0 270)
			(size 0.46 0.42)
			(layers "B.Cu" "B.Mask" "B.Paste")
			(net "NetC4_2")
			(solder_mask_margin 0.05)
			(solder_paste_margin 0)
		)
	)
	(footprint "Vault:TH000V_300DIAx400_001mt_9774040243R"
		(locked yes)
		(layer "B.Cu")
		(at 148.601105 126.603605 180)
		(property "Reference" "J1"
			(at -0.00185 4.13071 0)
			(unlocked yes)
			(layer "B.SilkS")
			(effects
				(font
					(face "Arial")
					(size 0.63 0.63)
					(thickness 0.254)
				)
				(justify mirror)
			)
		)
		(property "Value" "Wurth_9774040243R"
			(at 9.66063 -4.57418 0)
			(unlocked yes)
			(layer "B.SilkS")
			(hide yes)
			(effects
				(font
					(face "Arial")
					(size 0.63 0.63)
					(thickness 0.254)
				)
				(justify mirror)
			)
		)
		(sheetname "SCH_SA45_DaughterCard")
		(sheetfile "SCH_SA45_DaughterCard.kicad_sch")
		(duplicate_pad_numbers_are_jumpers no)
		(fp_line
			(start 3.1 3.1)
			(end -3.1 3.1)
			(stroke
				(width 0.1)
				(type solid)
			)
			(layer "B.CrtYd")
		)
		(fp_line
			(start 3.1 -3.1)
			(end 3.1 3.1)
			(stroke
				(width 0.1)
				(type solid)
			)
			(layer "B.CrtYd")
		)
		(fp_line
			(start 3.1 -3.1)
			(end -3.1 -3.1)
			(stroke
				(width 0.1)
				(type solid)
			)
			(layer "B.CrtYd")
		)
		(fp_line
			(start -3.1 -3.1)
			(end -3.1 3.1)
			(stroke
				(width 0.1)
				(type solid)
			)
			(layer "B.CrtYd")
		)
		(fp_circle
			(center 0 0)
			(end 0 1.5)
			(stroke
				(width 0.1)
				(type solid)
			)
			(fill no)
			(layer "B.Fab")
		)
		(fp_text user "${REFERENCE}"
			(at -0.00235 0.166251 360)
			(unlocked yes)
			(layer "B.Fab")
			(effects
				(font
					(face "Arial")
					(size 0.8001 0.8001)
					(thickness 0.254)
				)
				(justify mirror)
			)
		)
		(pad "" np_thru_hole circle
			(at 0 0 180)
			(size 5.3 5.3)
			(drill 3)
			(layers "*.Cu" "*.Mask")
			(solder_mask_margin 0.2)
			(solder_paste_margin -2147.48364)
			(thermal_bridge_angle 90)
		)
	)
	(footprint "Vault:CAPC2013X140N"
		(layer "B.Cu")
		(at 151.476105 115.053605 180)
		(property "Reference" "C10"
			(at -2.95163 0.12656 0)
			(unlocked yes)
			(layer "B.SilkS")
			(effects
				(font
					(face "Arial")
					(size 0.63 0.63)
					(thickness 0.254)
				)
				(justify mirror)
			)
		)
		(property "Value" "Murata_GRM21BR61A226ME51L"
			(at 21.20959 3.13786 0)
			(unlocked yes)
			(layer "B.SilkS")
			(hide yes)
			(effects
				(font
					(face "Arial")
					(size 0.63 0.63)
					(thickness 0.254)
				)
				(justify mirror)
			)
		)
		(sheetname "SCH_SA45_DaughterCard")
		(sheetfile "SCH_SA45_DaughterCard.kicad_sch")
		(duplicate_pad_numbers_are_jumpers no)
		(fp_line
			(start 1.8 1.1)
			(end -1.8 1.1)
			(stroke
				(width 0.1)
				(type solid)
			)
			(layer "B.CrtYd")
		)
		(fp_line
			(start 1.8 -1.1)
			(end 1.8 1.1)
			(stroke
				(width 0.1)
				(type solid)
			)
			(layer "B.CrtYd")
		)
		(fp_line
			(start 1.8 -1.1)
			(end -1.8 -1.1)
			(stroke
				(width 0.1)
				(type solid)
			)
			(layer "B.CrtYd")
		)
		(fp_line
			(start -1.8 -1.1)
			(end -1.8 1.1)
			(stroke
				(width 0.1)
				(type solid)
			)
			(layer "B.CrtYd")
		)
		(fp_line
			(start 1 0.65)
			(end -1 0.65)
			(stroke
				(width 0.05)
				(type solid)
			)
			(layer "B.Fab")
		)
		(fp_line
			(start 1 -0.65)
			(end 1 0.65)
			(stroke
				(width 0.05)
				(type solid)
			)
			(layer "B.Fab")
		)
		(fp_line
			(start 1 -0.65)
			(end -1 -0.65)
			(stroke
				(width 0.05)
				(type solid)
			)
			(layer "B.Fab")
		)
		(fp_line
			(start -1 -0.65)
			(end -1 0.65)
			(stroke
				(width 0.05)
				(type solid)
			)
			(layer "B.Fab")
		)
		(fp_text_box "${REFERENCE}"
			(start 1.09004 0.20729)
			(end -1.09004 -0.20729)
			(margins 0 0 0 0)
			(angle -180)
			(layer "B.Fab")
			(effects
				(font
					(face "Arial")
					(size 0.315 0.315)
					(thickness 0.254)
				)
				(justify top mirror)
			)
			(border no)
			(stroke
				(width 0.1)
				(type default)
			)
			(knockout no)
		)
		(pad "1" smd rect
			(at -0.9 0 180)
			(size 1.3 1.65)
			(layers "B.Cu" "B.Mask" "B.Paste")
			(net "+3.3V")
			(solder_mask_margin 0.05)
			(solder_paste_margin 0)
		)
		(pad "2" smd rect
			(at 0.9 0 180)
			(size 1.3 1.65)
			(layers "B.Cu" "B.Mask" "B.Paste")
			(net "GND")
			(solder_mask_margin 0.05)
			(solder_paste_margin 0)
		)
	)
	(footprint "Vault:FID_1p0mm"
		(layer "B.Cu")
		(at 171.351105 128.153605 180)
		(property "Reference" "Designator7"
			(at 7.084135 3.019298 0)
			(unlocked yes)
			(layer "B.SilkS")
			(hide yes)
			(effects
				(font
					(size 1.524 1.524)
					(thickness 0.254)
				)
				(justify mirror)
			)
		)
		(property "Value" "Comment"
			(at 5.07844 0.707898 0)
			(unlocked yes)
			(layer "B.SilkS")
			(hide yes)
			(effects
				(font
					(size 1.524 1.524)
					(thickness 0.254)
				)
				(justify mirror)
			)
		)
		(sheetfile ".kicad_sch")
		(duplicate_pad_numbers_are_jumpers no)
		(fp_circle
			(center 0 0)
			(end 0 1)
			(stroke
				(width 0.1)
				(type solid)
			)
			(fill no)
			(layer "B.CrtYd")
		)
		(pad "1" smd circle
			(at 0 0 90)
			(size 1 1)
			(layers "B.Cu" "B.Mask" "B.Paste")
			(solder_mask_margin 0.5)
			(solder_paste_margin -6)
			(thermal_bridge_angle 90)
		)
		(zone
			(layer "B.Cu")
			(hatch edge 0.5)
			(connect_pads
				(clearance 0)
			)
			(min_thickness 0.25)
			(keepout
				(tracks not_allowed)
				(vias not_allowed)
				(pads allowed)
				(copperpour not_allowed)
				(footprints allowed)
			)
			(placement
				(enabled no)
				(sheetname "")
			)
			(fill
				(thermal_gap 0.5)
				(thermal_bridge_width 0.5)
				(island_removal_mode 0)
			)
			(polygon
				(pts
					(xy 171.64139 127.196665) (xy 171.822502 127.271684) (xy 171.985498 127.380595) (xy 172.124115 127.519212)
					(xy 172.233026 127.682208) (xy 172.308045 127.86332) (xy 172.34629 128.055588) (xy 172.34629 128.251622)
					(xy 172.308045 128.44389) (xy 172.233026 128.625002) (xy 172.124115 128.787998) (xy 171.985498 128.926615)
					(xy 171.822502 129.035526) (xy 171.64139 129.110545) (xy 171.449122 129.14879) (xy 171.253088 129.14879)
					(xy 171.06082 129.110545) (xy 170.879708 129.035526) (xy 170.716712 128.926615) (xy 170.578095 128.787998)
					(xy 170.469184 128.625002) (xy 170.394165 128.44389) (xy 170.35592 128.251622) (xy 170.35592 128.087779)
					(xy 170.851105 128.087779) (xy 170.851105 128.219431) (xy 170.88518 128.346598) (xy 170.951006 128.460612)
					(xy 171.044098 128.553704) (xy 171.158112 128.61953) (xy 171.285279 128.653605) (xy 171.416931 128.653605)
					(xy 171.544098 128.61953) (xy 171.658112 128.553704) (xy 171.751204 128.460612) (xy 171.81703 128.346598)
					(xy 171.851105 128.219431) (xy 171.851105 128.087779) (xy 171.81703 127.960612) (xy 171.751204 127.846598)
					(xy 171.658112 127.753506) (xy 171.544098 127.68768) (xy 171.416931 127.653605) (xy 171.285279 127.653605)
					(xy 171.158112 127.68768) (xy 171.044098 127.753506) (xy 170.951006 127.846598) (xy 170.88518 127.960612)
					(xy 170.851105 128.087779) (xy 170.35592 128.087779) (xy 170.35592 128.055588) (xy 170.394165 127.86332)
					(xy 170.469184 127.682208) (xy 170.578095 127.519212) (xy 170.716712 127.380595) (xy 170.879708 127.271684)
					(xy 171.06082 127.196665) (xy 171.253088 127.15842) (xy 171.449122 127.15842)
				)
			)
		)
	)
	(footprint "Vault:CAPC1005X055N"
		(layer "B.Cu")
		(at 151.576105 113.053605 180)
		(property "Reference" "C12"
			(at -2.85163 0.12655 0)
			(unlocked yes)
			(layer "B.SilkS")
			(effects
				(font
					(face "Arial")
					(size 0.63 0.63)
					(thickness 0.254)
				)
				(justify mirror)
			)
		)
		(property "Value" "Murata_GRM155R61H104KE14D"
			(at 25.338025 1.61026 0)
			(unlocked yes)
			(layer "B.SilkS")
			(hide yes)
			(effects
				(font
					(face "Arial")
					(size 0.63 0.63)
					(thickness 0.254)
				)
				(justify mirror)
			)
		)
		(sheetname "SCH_SA45_DaughterCard")
		(sheetfile "SCH_SA45_DaughterCard.kicad_sch")
		(duplicate_pad_numbers_are_jumpers no)
		(fp_line
			(start 0.95 0.5)
			(end -0.95 0.5)
			(stroke
				(width 0.1)
				(type solid)
			)
			(layer "B.CrtYd")
		)
		(fp_line
			(start 0.95 -0.5)
			(end 0.95 0.5)
			(stroke
				(width 0.1)
				(type solid)
			)
			(layer "B.CrtYd")
		)
		(fp_line
			(start 0.95 -0.5)
			(end -0.95 -0.5)
			(stroke
				(width 0.1)
				(type solid)
			)
			(layer "B.CrtYd")
		)
		(fp_line
			(start -0.95 -0.5)
			(end -0.95 0.5)
			(stroke
				(width 0.1)
				(type solid)
			)
			(layer "B.CrtYd")
		)
		(fp_line
			(start 0.5 0.25)
			(end -0.5 0.25)
			(stroke
				(width 0.05)
				(type solid)
			)
			(layer "B.Fab")
		)
		(fp_line
			(start 0.5 -0.25)
			(end 0.5 0.25)
			(stroke
				(width 0.05)
				(type solid)
			)
			(layer "B.Fab")
		)
		(fp_line
			(start 0.5 -0.25)
			(end -0.5 -0.25)
			(stroke
				(width 0.05)
				(type solid)
			)
			(layer "B.Fab")
		)
		(fp_line
			(start -0.5 -0.25)
			(end -0.5 0.25)
			(stroke
				(width 0.05)
				(type solid)
			)
			(layer "B.Fab")
		)
		(fp_text_box "${REFERENCE}"
			(start 1.09004 0.20727)
			(end -1.09004 -0.20726)
			(margins 0 0 0 0)
			(angle -180)
			(layer "B.Fab")
			(effects
				(font
					(face "Arial")
					(size 0.315 0.315)
					(thickness 0.254)
				)
				(justify top mirror)
			)
			(border no)
			(stroke
				(width 0.1)
				(type default)
			)
			(knockout no)
		)
		(pad "1" smd rect
			(at -0.46 0 180)
			(size 0.6 0.62)
			(layers "B.Cu" "B.Mask" "B.Paste")
			(net "+3.3V")
			(solder_mask_margin 0.05)
			(solder_paste_margin 0)
		)
		(pad "2" smd rect
			(at 0.46 0 180)
			(size 0.6 0.62)
			(layers "B.Cu" "B.Mask" "B.Paste")
			(net "GND")
			(solder_mask_margin 0.05)
			(solder_paste_margin 0)
		)
	)
	(footprint "FAB_SA45_DaughterCard:DiodesInc_AP63356QZV-7"
		(layer "B.Cu")
		(at 145.326105 107.378605)
		(property "Reference" "U3"
			(at -2.450005 1.84429 0)
			(unlocked yes)
			(layer "B.SilkS")
			(effects
				(font
					(face "Arial")
					(size 0.63 0.63)
					(thickness 0.254)
				)
				(justify mirror)
			)
		)
		(property "Value" "DiodesInc_AP63356QZV-7"
			(at 6.94796 31.32414 0)
			(unlocked yes)
			(layer "B.SilkS")
			(hide yes)
			(effects
				(font
					(face "Arial")
					(size 0.63 0.63)
					(thickness 0.254)
				)
				(justify mirror)
			)
		)
		(sheetname "SCH_SA45_DaughterCard")
		(sheetfile "SCH_SA45_DaughterCard.kicad_sch")
		(duplicate_pad_numbers_are_jumpers no)
		(fp_rect
			(start -1.19996 0.22787)
			(end -0.49996 -1.17501)
			(stroke
				(width 0)
				(type default)
			)
			(fill yes)
			(layer "B.Mask")
		)
		(fp_rect
			(start 0.49996 0.22499)
			(end 1.19996 -1.17501)
			(stroke
				(width 0)
				(type default)
			)
			(fill yes)
			(layer "B.Mask")
		)
		(fp_line
			(start -1.4 -1.33125)
			(end 1.4 -1.33125)
			(stroke
				(width 0.1)
				(type solid)
			)
			(layer "B.CrtYd")
		)
		(fp_line
			(start -1.4 0.66874)
			(end -1.4 -1.33125)
			(stroke
				(width 0.1)
				(type solid)
			)
			(layer "B.CrtYd")
		)
		(fp_line
			(start -1.4 2.26875)
			(end -1.4 0.66874)
			(stroke
				(width 0.1)
				(type solid)
			)
			(layer "B.CrtYd")
		)
		(fp_line
			(start -1.4 2.26875)
			(end 1.3 2.26875)
			(stroke
				(width 0.1)
				(type solid)
			)
			(layer "B.CrtYd")
		)
		(fp_line
			(start 1.3 2.26875)
			(end 1.4 2.26875)
			(stroke
				(width 0.1)
				(type solid)
			)
			(layer "B.CrtYd")
		)
		(fp_line
			(start 1.4 2.26875)
			(end 1.4 -1.33125)
			(stroke
				(width 0.1)
				(type solid)
			)
			(layer "B.CrtYd")
		)
		(fp_text user "${REFERENCE}"
			(at -0.000005 -0.06197 360)
			(unlocked yes)
			(layer "B.Fab")
			(effects
				(font
					(face "Arial")
					(size 0.63 0.63)
					(thickness 0.254)
				)
				(justify mirror)
			)
		)
		(fp_text user ""
			(at 0.367795 0.63442 180)
			(unlocked yes)
			(layer "B.Fab")
			(effects
				(font
					(face "Arial")
					(size 0.63 0.63)
					(thickness 0.254)
				)
				(justify mirror)
			)
		)
		(pad "1" smd rect
			(at -0.75 0.975)
			(size 0.8 1.45)
			(layers "B.Cu" "B.Mask" "B.Paste")
			(net "+5V")
			(solder_mask_margin 0.05)
			(solder_paste_margin 0)
		)
		(pad "2" smd rect
			(at -0.85 -0.075)
			(size 0.6 0.3)
			(layers "B.Cu" "B.Mask" "B.Paste")
			(net "+5V")
			(solder_mask_margin 0.05)
			(solder_paste_margin 0)
		)
		(pad "3" smd rect
			(at -0.85 -0.525)
			(size 0.6 0.3)
			(layers "B.Cu" "B.Mask" "B.Paste")
			(net "NetC4_2")
			(solder_mask_margin 0.05)
			(solder_paste_margin 0)
		)
		(pad "4" smd rect
			(at -0.85 -0.975)
			(size 0.6 0.3)
			(layers "B.Cu" "B.Mask" "B.Paste")
			(net "NetR5_1")
			(solder_mask_margin 0.05)
			(solder_paste_margin 0)
		)
		(pad "5" smd rect
			(at 0.85 -0.975)
			(size 0.6 0.3)
			(layers "B.Cu" "B.Mask" "B.Paste")
			(solder_mask_margin 0.05)
			(solder_paste_margin 0)
		)
		(pad "6" smd rect
			(at 0.85 -0.525)
			(size 0.6 0.3)
			(layers "B.Cu" "B.Mask" "B.Paste")
			(net "NetC3_1")
			(solder_mask_margin 0.05)
			(solder_paste_margin 0)
		)
		(pad "7" smd rect
			(at 0.85 -0.075)
			(size 0.6 0.3)
			(layers "B.Cu" "B.Mask" "B.Paste")
			(net "SW")
			(solder_mask_margin 0.05)
			(solder_paste_margin 0)
		)
		(pad "8" smd rect
			(at 0.75 0.975)
			(size 0.8 1.45)
			(layers "B.Cu" "B.Mask" "B.Paste")
			(net "GND")
			(solder_mask_margin 0.05)
			(solder_paste_margin 0)
		)
		(pad "9" smd rect
			(at 0 1.1125)
			(size 0.3 1.725)
			(layers "B.Cu" "B.Mask" "B.Paste")
			(net "SW")
			(solder_mask_margin 0.05)
			(solder_paste_margin 0)
		)
	)
	(footprint "Vault:CAPC1005X055N"
		(layer "B.Cu")
		(at 146.841105 104.168605)
		(property "Reference" "C3"
			(at 0.4475 -1.15335 0)
			(unlocked yes)
			(layer "B.SilkS")
			(effects
				(font
					(face "Arial")
					(size 0.63 0.63)
					(thickness 0.254)
				)
				(justify mirror)
			)
		)
		(property "Value" "Murata_GRM155R61H104KE14D"
			(at -0.824235 18.44158 0)
			(unlocked yes)
			(layer "B.SilkS")
			(hide yes)
			(effects
				(font
					(face "Arial")
					(size 0.63 0.63)
					(thickness 0.254)
				)
				(justify mirror)
			)
		)
		(sheetname "SCH_SA45_DaughterCard")
		(sheetfile "SCH_SA45_DaughterCard.kicad_sch")
		(duplicate_pad_numbers_are_jumpers no)
		(fp_line
			(start -0.95 -0.5)
			(end 0.95 -0.5)
			(stroke
				(width 0.1)
				(type solid)
			)
			(layer "B.CrtYd")
		)
		(fp_line
			(start -0.95 0.5)
			(end -0.95 -0.5)
			(stroke
				(width 0.1)
				(type solid)
			)
			(layer "B.CrtYd")
		)
		(fp_line
			(start -0.95 0.5)
			(end 0.95 0.5)
			(stroke
				(width 0.1)
				(type solid)
			)
			(layer "B.CrtYd")
		)
		(fp_line
			(start 0.95 0.5)
			(end 0.95 -0.5)
			(stroke
				(width 0.1)
				(type solid)
			)
			(layer "B.CrtYd")
		)
		(fp_line
			(start -0.5 -0.25)
			(end 0.5 -0.25)
			(stroke
				(width 0.05)
				(type solid)
			)
			(layer "B.Fab")
		)
		(fp_line
			(start -0.5 0.25)
			(end -0.5 -0.25)
			(stroke
				(width 0.05)
				(type solid)
			)
			(layer "B.Fab")
		)
		(fp_line
			(start -0.5 0.25)
			(end 0.5 0.25)
			(stroke
				(width 0.05)
				(type solid)
			)
			(layer "B.Fab")
		)
		(fp_line
			(start 0.5 0.25)
			(end 0.5 -0.25)
			(stroke
				(width 0.05)
				(type solid)
			)
			(layer "B.Fab")
		)
		(fp_text_box "${REFERENCE}"
			(start 1.14717 0.20757)
			(end -1.14713 -0.20756)
			(margins 0 0 0 0)
			(angle 180)
			(layer "B.Fab")
			(effects
				(font
					(face "Arial")
					(size 0.315 0.315)
					(thickness 0.254)
				)
				(justify top mirror)
			)
			(border no)
			(stroke
				(width 0.1)
				(type default)
			)
			(knockout no)
		)
		(pad "1" smd rect
			(at -0.46 0)
			(size 0.6 0.62)
			(layers "B.Cu" "B.Mask" "B.Paste")
			(net "NetC3_1")
			(solder_mask_margin 0.05)
			(solder_paste_margin 0)
		)
		(pad "2" smd rect
			(at 0.46 0)
			(size 0.6 0.62)
			(layers "B.Cu" "B.Mask" "B.Paste")
			(net "SW")
			(solder_mask_margin 0.05)
			(solder_paste_margin 0)
		)
	)
	(footprint "FAB_SA45_DaughterCard:Keystone_4871"
		(locked yes)
		(layer "B.Cu")
		(at 132.561105 123.343605 180)
		(property "Reference" "J3"
			(at -4.076845 0.18071 0)
			(unlocked yes)
			(layer "B.SilkS")
			(effects
				(font
					(face "Arial")
					(size 0.63 0.63)
					(thickness 0.254)
				)
				(justify mirror)
			)
		)
		(property "Value" "Keystone_4871"
			(at 6.3343 -5.019802 0)
			(unlocked yes)
			(layer "B.SilkS")
			(hide yes)
			(effects
				(font
					(size 1.524 1.524)
					(thickness 0.254)
				)
				(justify mirror)
			)
		)
		(sheetname "SCH_SA45_DaughterCard")
		(sheetfile "SCH_SA45_DaughterCard.kicad_sch")
		(duplicate_pad_numbers_are_jumpers no)
		(fp_line
			(start 3.4 3.4)
			(end -3.4 3.4)
			(stroke
				(width 0.1)
				(type solid)
			)
			(layer "B.CrtYd")
		)
		(fp_line
			(start 3.4 -3.4)
			(end 3.4 3.4)
			(stroke
				(width 0.1)
				(type solid)
			)
			(layer "B.CrtYd")
		)
		(fp_line
			(start 3.4 -3.4)
			(end -3.4 -3.4)
			(stroke
				(width 0.1)
				(type solid)
			)
			(layer "B.CrtYd")
		)
		(fp_line
			(start -3.4 -0.8)
			(end -3.4 3.4)
			(stroke
				(width 0.1)
				(type solid)
			)
			(layer "B.CrtYd")
		)
		(fp_line
			(start -3.4 -3.4)
			(end -3.4 -0.8)
			(stroke
				(width 0.1)
				(type solid)
			)
			(layer "B.CrtYd")
		)
		(fp_text user ""
			(at 0.367795 0.63446 360)
			(unlocked yes)
			(layer "B.Fab")
			(effects
				(font
					(face "Arial")
					(size 0.63 0.63)
					(thickness 0.254)
				)
				(justify mirror)
			)
		)
		(fp_text user "${REFERENCE}"
			(at -0.001845 0.19946 360)
			(unlocked yes)
			(layer "B.Fab")
			(effects
				(font
					(face "Arial")
					(size 0.63 0.63)
					(thickness 0.254)
				)
				(justify mirror)
			)
		)
		(pad "Hole" thru_hole circle
			(at 0 0 180)
			(size 0 0)
			(drill 3.7)
			(layers "*.Cu" "*.Mask")
			(remove_unused_layers no)
			(thermal_bridge_angle 90)
		)
		(pad "MT" smd circle
			(at 0 0 180)
			(size 6.2 6.2)
			(layers "B.Cu" "B.Mask" "B.Paste")
			(solder_mask_margin 0.05)
			(thermal_bridge_angle 90)
		)
	)
	(footprint "Vault:CAPC2013X145N"
		(layer "B.Cu")
		(at 144.976105 115.553605)
		(property "Reference" "C5"
			(at -2.69615 -0.12655 0)
			(unlocked yes)
			(layer "B.SilkS")
			(effects
				(font
					(face "Arial")
					(size 0.63 0.63)
					(thickness 0.254)
				)
				(justify mirror)
			)
		)
		(property "Value" "Murata_GRM21BR6YA106KE43L"
			(at -22.39585 -6.2605 0)
			(unlocked yes)
			(layer "B.SilkS")
			(hide yes)
			(effects
				(font
					(face "Arial")
					(size 0.63 0.63)
					(thickness 0.254)
				)
				(justify mirror)
			)
		)
		(sheetname "SCH_SA45_DaughterCard")
		(sheetfile "SCH_SA45_DaughterCard.kicad_sch")
		(duplicate_pad_numbers_are_jumpers no)
		(fp_line
			(start -1.8 -1.1)
			(end 1.8 -1.1)
			(stroke
				(width 0.1)
				(type solid)
			)
			(layer "B.CrtYd")
		)
		(fp_line
			(start -1.8 1.1)
			(end -1.8 -1.1)
			(stroke
				(width 0.1)
				(type solid)
			)
			(layer "B.CrtYd")
		)
		(fp_line
			(start -1.8 1.1)
			(end 1.8 1.1)
			(stroke
				(width 0.1)
				(type solid)
			)
			(layer "B.CrtYd")
		)
		(fp_line
			(start 1.8 1.1)
			(end 1.8 -1.1)
			(stroke
				(width 0.1)
				(type solid)
			)
			(layer "B.CrtYd")
		)
		(fp_line
			(start -1 -0.65)
			(end 1 -0.65)
			(stroke
				(width 0.05)
				(type solid)
			)
			(layer "B.Fab")
		)
		(fp_line
			(start -1 0.65)
			(end -1 -0.65)
			(stroke
				(width 0.05)
				(type solid)
			)
			(layer "B.Fab")
		)
		(fp_line
			(start -1 0.65)
			(end 1 0.65)
			(stroke
				(width 0.05)
				(type solid)
			)
			(layer "B.Fab")
		)
		(fp_line
			(start 1 0.65)
			(end 1 -0.65)
			(stroke
				(width 0.05)
				(type solid)
			)
			(layer "B.Fab")
		)
		(fp_text_box "${REFERENCE}"
			(start 1.14717 0.20754)
			(end -1.14713 -0.20759)
			(margins 0 0 0 0)
			(angle 180)
			(layer "B.Fab")
			(effects
				(font
					(face "Arial")
					(size 0.315 0.315)
					(thickness 0.254)
				)
				(justify top mirror)
			)
			(border no)
			(stroke
				(width 0.1)
				(type default)
			)
			(knockout no)
		)
		(pad "1" smd rect
			(at -0.9 0)
			(size 1.3 1.65)
			(layers "B.Cu" "B.Mask" "B.Paste")
			(net "+5V")
			(solder_mask_margin 0.05)
			(solder_paste_margin 0)
		)
		(pad "2" smd rect
			(at 0.9 0)
			(size 1.3 1.65)
			(layers "B.Cu" "B.Mask" "B.Paste")
			(net "GND")
			(solder_mask_margin 0.05)
			(solder_paste_margin 0)
		)
	)
	(footprint "FAB_SA45_DaughterCard:Eaton_HCM0703-4R7-R"
		(layer "B.Cu")
		(at 151.576105 108.491105)
		(property "Reference" "L1"
			(at 5.124995 -0.06267 0)
			(unlocked yes)
			(layer "B.SilkS")
			(effects
				(font
					(face "Arial")
					(size 0.63 0.63)
					(thickness 0.254)
				)
				(justify mirror)
			)
		)
		(property "Value" "4.7uH"
			(at -1.46809 3.72341 0)
			(unlocked yes)
			(layer "B.SilkS")
			(hide yes)
			(effects
				(font
					(face "Arial")
					(size 0.63 0.63)
					(thickness 0.254)
				)
				(justify mirror)
			)
		)
		(sheetname "SCH_SA45_DaughterCard")
		(sheetfile "SCH_SA45_DaughterCard.kicad_sch")
		(duplicate_pad_numbers_are_jumpers no)
		(fp_line
			(start -4 -3.5)
			(end 4 -3.5)
			(stroke
				(width 0.1)
				(type solid)
			)
			(layer "B.CrtYd")
		)
		(fp_line
			(start -4 -0.8)
			(end -4 -3.5)
			(stroke
				(width 0.1)
				(type solid)
			)
			(layer "B.CrtYd")
		)
		(fp_line
			(start -4 3.5)
			(end -4 -0.8)
			(stroke
				(width 0.1)
				(type solid)
			)
			(layer "B.CrtYd")
		)
		(fp_line
			(start -4 3.5)
			(end 4 3.5)
			(stroke
				(width 0.1)
				(type solid)
			)
			(layer "B.CrtYd")
		)
		(fp_line
			(start 4 3.5)
			(end 4 -3.5)
			(stroke
				(width 0.1)
				(type solid)
			)
			(layer "B.CrtYd")
		)
		(fp_text user "${REFERENCE}"
			(at -0.000005 0.19391 180)
			(unlocked yes)
			(layer "B.Fab")
			(effects
				(font
					(face "Arial")
					(size 0.63 0.63)
					(thickness 0.254)
				)
				(justify mirror)
			)
		)
		(fp_text user ""
			(at 0.367795 0.63446 180)
			(unlocked yes)
			(layer "B.Fab")
			(effects
				(font
					(face "Arial")
					(size 0.63 0.63)
					(thickness 0.254)
				)
				(justify mirror)
			)
		)
		(pad "1" smd rect
			(at -2.65 0)
			(size 2.3 3.3)
			(layers "B.Cu" "B.Mask" "B.Paste")
			(net "SW")
			(solder_mask_margin 0.05)
			(solder_paste_margin 0)
		)
		(pad "2" smd rect
			(at 2.65 0)
			(size 2.3 3.3)
			(layers "B.Cu" "B.Mask" "B.Paste")
			(net "+3.3V")
			(solder_mask_margin 0.05)
			(solder_paste_margin 0)
		)
	)
	(footprint "Vault:TH001V_109DIA_000mt_8600-0"
		(layer "B.Cu")
		(at 168.841105 125.343605 180)
		(property "Reference" "P1"
			(at 0 1.96517 0)
			(unlocked yes)
			(layer "B.SilkS")
			(effects
				(font
					(face "Arial")
					(size 0.63 0.63)
					(thickness 0.254)
				)
				(justify mirror)
			)
		)
		(property "Value" "Mill-Max_8600-0-05-80-00-00-03-0"
			(at 22.534825 -2.89778 0)
			(unlocked yes)
			(layer "B.SilkS")
			(hide yes)
			(effects
				(font
					(face "Arial")
					(size 0.63 0.63)
					(thickness 0.254)
				)
				(justify mirror)
			)
		)
		(sheetname "SCH_SA45_DaughterCard")
		(sheetfile "SCH_SA45_DaughterCard.kicad_sch")
		(duplicate_pad_numbers_are_jumpers no)
		(fp_line
			(start 1.4 1.4)
			(end -1.4 1.4)
			(stroke
				(width 0.1)
				(type solid)
			)
			(layer "B.CrtYd")
		)
		(fp_line
			(start 1.4 -1.4)
			(end 1.4 1.4)
			(stroke
				(width 0.1)
				(type solid)
			)
			(layer "B.CrtYd")
		)
		(fp_line
			(start 1.4 -1.4)
			(end -1.4 -1.4)
			(stroke
				(width 0.1)
				(type solid)
			)
			(layer "B.CrtYd")
		)
		(fp_line
			(start -1.4 -1.4)
			(end -1.4 1.4)
			(stroke
				(width 0.1)
				(type solid)
			)
			(layer "B.CrtYd")
		)
		(fp_circle
			(center 0 0)
			(end 0 0.545)
			(stroke
				(width 0.1)
				(type solid)
			)
			(fill no)
			(layer "B.Fab")
		)
		(fp_text user "${REFERENCE}"
			(at 0 0.159211 360)
			(unlocked yes)
			(layer "B.Fab")
			(effects
				(font
					(face "Arial")
					(size 0.8001 0.8001)
					(thickness 0.254)
				)
				(justify mirror)
			)
		)
		(pad "1" thru_hole circle
			(at 0.04 0 180)
			(size 2.09 2.09)
			(drill 1.09)
			(layers "*.Cu" "*.Mask")
			(remove_unused_layers no)
			(net "NC")
			(solder_mask_margin 0.05)
			(solder_paste_margin -2147.48364)
			(thermal_bridge_angle 90)
		)
	)
	(footprint "FAB_SA45_DaughterCard:Keystone_4871"
		(locked yes)
		(layer "B.Cu")
		(at 164.361105 85.243605 180)
		(property "Reference" "J5"
			(at 3.97315 0.1321 0)
			(unlocked yes)
			(layer "B.SilkS")
			(effects
				(font
					(face "Arial")
					(size 0.63 0.63)
					(thickness 0.254)
				)
				(justify mirror)
			)
		)
		(property "Value" "Keystone_4871"
			(at 6.3343 -5.019802 0)
			(unlocked yes)
			(layer "B.SilkS")
			(hide yes)
			(effects
				(font
					(size 1.524 1.524)
					(thickness 0.254)
				)
				(justify mirror)
			)
		)
		(sheetname "SCH_SA45_DaughterCard")
		(sheetfile "SCH_SA45_DaughterCard.kicad_sch")
		(duplicate_pad_numbers_are_jumpers no)
		(fp_line
			(start 3.4 3.4)
			(end -3.4 3.4)
			(stroke
				(width 0.1)
				(type solid)
			)
			(layer "B.CrtYd")
		)
		(fp_line
			(start 3.4 -3.4)
			(end 3.4 3.4)
			(stroke
				(width 0.1)
				(type solid)
			)
			(layer "B.CrtYd")
		)
		(fp_line
			(start 3.4 -3.4)
			(end -3.4 -3.4)
			(stroke
				(width 0.1)
				(type solid)
			)
			(layer "B.CrtYd")
		)
		(fp_line
			(start -3.4 -0.8)
			(end -3.4 3.4)
			(stroke
				(width 0.1)
				(type solid)
			)
			(layer "B.CrtYd")
		)
		(fp_line
			(start -3.4 -3.4)
			(end -3.4 -0.8)
			(stroke
				(width 0.1)
				(type solid)
			)
			(layer "B.CrtYd")
		)
		(fp_text user ""
			(at 0.367795 0.63446 360)
			(unlocked yes)
			(layer "B.Fab")
			(effects
				(font
					(face "Arial")
					(size 0.63 0.63)
					(thickness 0.254)
				)
				(justify mirror)
			)
		)
		(fp_text user "${REFERENCE}"
			(at -0.00185 0.20085 360)
			(unlocked yes)
			(layer "B.Fab")
			(effects
				(font
					(face "Arial")
					(size 0.63 0.63)
					(thickness 0.254)
				)
				(justify mirror)
			)
		)
		(pad "Hole" thru_hole circle
			(at 0 0 180)
			(size 0 0)
			(drill 3.7)
			(layers "*.Cu" "*.Mask")
			(remove_unused_layers no)
			(thermal_bridge_angle 90)
		)
		(pad "MT" smd circle
			(at 0 0 180)
			(size 6.2 6.2)
			(layers "B.Cu" "B.Mask" "B.Paste")
			(solder_mask_margin 0.05)
			(thermal_bridge_angle 90)
		)
	)
	(footprint "Vault:TH001V_109DIA_000mt_8600-0"
		(layer "B.Cu")
		(at 136.335105 81.993605 180)
		(property "Reference" "P8"
			(at 0 -1.93857 0)
			(unlocked yes)
			(layer "B.SilkS")
			(effects
				(font
					(face "Arial")
					(size 0.63 0.63)
					(thickness 0.254)
				)
				(justify mirror)
			)
		)
		(property "Value" "Mill-Max_8600-0-05-80-00-00-03-0"
			(at 22.534825 -2.89778 0)
			(unlocked yes)
			(layer "B.SilkS")
			(hide yes)
			(effects
				(font
					(face "Arial")
					(size 0.63 0.63)
					(thickness 0.254)
				)
				(justify mirror)
			)
		)
		(sheetname "SCH_SA45_DaughterCard")
		(sheetfile "SCH_SA45_DaughterCard.kicad_sch")
		(duplicate_pad_numbers_are_jumpers no)
		(fp_line
			(start 1.4 1.4)
			(end -1.4 1.4)
			(stroke
				(width 0.1)
				(type solid)
			)
			(layer "B.CrtYd")
		)
		(fp_line
			(start 1.4 -1.4)
			(end 1.4 1.4)
			(stroke
				(width 0.1)
				(type solid)
			)
			(layer "B.CrtYd")
		)
		(fp_line
			(start 1.4 -1.4)
			(end -1.4 -1.4)
			(stroke
				(width 0.1)
				(type solid)
			)
			(layer "B.CrtYd")
		)
		(fp_line
			(start -1.4 -1.4)
			(end -1.4 1.4)
			(stroke
				(width 0.1)
				(type solid)
			)
			(layer "B.CrtYd")
		)
		(fp_circle
			(center 0 0)
			(end 0 0.545)
			(stroke
				(width 0.1)
				(type solid)
			)
			(fill no)
			(layer "B.Fab")
		)
		(fp_text user "${REFERENCE}"
			(at 0 0.166251 360)
			(unlocked yes)
			(layer "B.Fab")
			(effects
				(font
					(face "Arial")
					(size 0.8001 0.8001)
					(thickness 0.254)
				)
				(justify mirror)
			)
		)
		(pad "1" thru_hole circle
			(at 0 -0.02 180)
			(size 2.09 2.09)
			(drill 1.09)
			(layers "*.Cu" "*.Mask")
			(remove_unused_layers no)
			(net "RX")
			(solder_mask_margin 0.05)
			(solder_paste_margin -2147.48364)
			(thermal_bridge_angle 90)
		)
	)
	(footprint "Vault:TH001V_109DIA_000mt_8600-0"
		(layer "B.Cu")
		(at 128.161105 84.663605 180)
		(property "Reference" "P4"
			(at 0 -1.71351 0)
			(unlocked yes)
			(layer "B.SilkS")
			(effects
				(font
					(face "Arial")
					(size 0.63 0.63)
					(thickness 0.254)
				)
				(justify mirror)
			)
		)
		(property "Value" "Mill-Max_8600-0-05-80-00-00-03-0"
			(at 22.534825 -2.89778 0)
			(unlocked yes)
			(layer "B.SilkS")
			(hide yes)
			(effects
				(font
					(face "Arial")
					(size 0.63 0.63)
					(thickness 0.254)
				)
				(justify mirror)
			)
		)
		(sheetname "SCH_SA45_DaughterCard")
		(sheetfile "SCH_SA45_DaughterCard.kicad_sch")
		(duplicate_pad_numbers_are_jumpers no)
		(fp_line
			(start 1.4 1.4)
			(end -1.4 1.4)
			(stroke
				(width 0.1)
				(type solid)
			)
			(layer "B.CrtYd")
		)
		(fp_line
			(start 1.4 -1.4)
			(end 1.4 1.4)
			(stroke
				(width 0.1)
				(type solid)
			)
			(layer "B.CrtYd")
		)
		(fp_line
			(start 1.4 -1.4)
			(end -1.4 -1.4)
			(stroke
				(width 0.1)
				(type solid)
			)
			(layer "B.CrtYd")
		)
		(fp_line
			(start -1.4 -1.4)
			(end -1.4 1.4)
			(stroke
				(width 0.1)
				(type solid)
			)
			(layer "B.CrtYd")
		)
		(fp_circle
			(center 0 0)
			(end 0 0.545)
			(stroke
				(width 0.1)
				(type solid)
			)
			(fill no)
			(layer "B.Fab")
		)
		(fp_text user "${REFERENCE}"
			(at 0 0.160971 360)
			(unlocked yes)
			(layer "B.Fab")
			(effects
				(font
					(face "Arial")
					(size 0.8001 0.8001)
					(thickness 0.254)
				)
				(justify mirror)
			)
		)
		(pad "1" thru_hole circle
			(at 0 -0.04 180)
			(size 2.09 2.09)
			(drill 1.09)
			(layers "*.Cu" "*.Mask")
			(remove_unused_layers no)
			(net "GND")
			(solder_mask_margin 0.05)
			(solder_paste_margin -2147.48364)
			(thermal_bridge_angle 90)
		)
	)
	(footprint "Vault:TH001V_109DIA_000mt_8600-0"
		(layer "B.Cu")
		(at 128.161105 125.343605 180)
		(property "Reference" "P5"
			(at 0 2.1471 0)
			(unlocked yes)
			(layer "B.SilkS")
			(effects
				(font
					(face "Arial")
					(size 0.63 0.63)
					(thickness 0.254)
				)
				(justify mirror)
			)
		)
		(property "Value" "Mill-Max_8600-0-05-80-00-00-03-0"
			(at 22.534825 -2.89778 0)
			(unlocked yes)
			(layer "B.SilkS")
			(hide yes)
			(effects
				(font
					(face "Arial")
					(size 0.63 0.63)
					(thickness 0.254)
				)
				(justify mirror)
			)
		)
		(sheetname "SCH_SA45_DaughterCard")
		(sheetfile "SCH_SA45_DaughterCard.kicad_sch")
		(duplicate_pad_numbers_are_jumpers no)
		(fp_line
			(start 1.4 1.4)
			(end -1.4 1.4)
			(stroke
				(width 0.1)
				(type solid)
			)
			(layer "B.CrtYd")
		)
		(fp_line
			(start 1.4 -1.4)
			(end 1.4 1.4)
			(stroke
				(width 0.1)
				(type solid)
			)
			(layer "B.CrtYd")
		)
		(fp_line
			(start 1.4 -1.4)
			(end -1.4 -1.4)
			(stroke
				(width 0.1)
				(type solid)
			)
			(layer "B.CrtYd")
		)
		(fp_line
			(start -1.4 -1.4)
			(end -1.4 1.4)
			(stroke
				(width 0.1)
				(type solid)
			)
			(layer "B.CrtYd")
		)
		(fp_circle
			(center 0 0)
			(end 0 0.545)
			(stroke
				(width 0.1)
				(type solid)
			)
			(fill no)
			(layer "B.Fab")
		)
		(fp_text user "${REFERENCE}"
			(at 0.000005 0.168011 360)
			(unlocked yes)
			(layer "B.Fab")
			(effects
				(font
					(face "Arial")
					(size 0.8001 0.8001)
					(thickness 0.254)
				)
				(justify mirror)
			)
		)
		(pad "1" thru_hole circle
			(at 0 0 180)
			(size 2.09 2.09)
			(drill 1.09)
			(layers "*.Cu" "*.Mask")
			(remove_unused_layers no)
			(net "+5V")
			(solder_mask_margin 0.05)
			(solder_paste_margin -2147.48364)
			(thermal_bridge_angle 90)
		)
	)
	(footprint "Vault:RESC1005X040N"
		(layer "B.Cu")
		(at 142.546105 107.328605 180)
		(property "Reference" "R4"
			(at 2.32 0.12263 0)
			(unlocked yes)
			(layer "B.SilkS")
			(effects
				(font
					(face "Arial")
					(size 0.63 0.63)
					(thickness 0.254)
				)
				(justify mirror)
			)
		)
		(property "Value" "Yageo_RC0402FR-0730KL"
			(at 5.42454 -8.62942 0)
			(unlocked yes)
			(layer "B.SilkS")
			(hide yes)
			(effects
				(font
					(face "Arial")
					(size 0.63 0.63)
					(thickness 0.254)
				)
				(justify mirror)
			)
		)
		(sheetname "SCH_SA45_DaughterCard")
		(sheetfile "SCH_SA45_DaughterCard.kicad_sch")
		(duplicate_pad_numbers_are_jumpers no)
		(fp_line
			(start 0.95 0.5)
			(end -0.95 0.5)
			(stroke
				(width 0.1)
				(type solid)
			)
			(layer "B.CrtYd")
		)
		(fp_line
			(start 0.95 -0.5)
			(end 0.95 0.5)
			(stroke
				(width 0.1)
				(type solid)
			)
			(layer "B.CrtYd")
		)
		(fp_line
			(start 0.95 -0.5)
			(end -0.95 -0.5)
			(stroke
				(width 0.1)
				(type solid)
			)
			(layer "B.CrtYd")
		)
		(fp_line
			(start -0.95 -0.5)
			(end -0.95 0.5)
			(stroke
				(width 0.1)
				(type solid)
			)
			(layer "B.CrtYd")
		)
		(fp_line
			(start 0.5 0.25)
			(end -0.5 0.25)
			(stroke
				(width 0.05)
				(type solid)
			)
			(layer "B.Fab")
		)
		(fp_line
			(start 0.5 -0.25)
			(end 0.5 0.25)
			(stroke
				(width 0.05)
				(type solid)
			)
			(layer "B.Fab")
		)
		(fp_line
			(start 0.5 -0.25)
			(end -0.5 -0.25)
			(stroke
				(width 0.05)
				(type solid)
			)
			(layer "B.Fab")
		)
		(fp_line
			(start -0.5 -0.25)
			(end -0.5 0.25)
			(stroke
				(width 0.05)
				(type solid)
			)
			(layer "B.Fab")
		)
		(fp_text_box "${REFERENCE}"
			(start 1.09004 0.20727)
			(end -1.09004 -0.20726)
			(margins 0 0 0 0)
			(angle -180)
			(layer "B.Fab")
			(effects
				(font
					(face "Arial")
					(size 0.315 0.315)
					(thickness 0.254)
				)
				(justify top mirror)
			)
			(border no)
			(stroke
				(width 0.1)
				(type default)
			)
			(knockout no)
		)
		(pad "1" smd rect
			(at -0.48 0 180)
			(size 0.57 0.62)
			(layers "B.Cu" "B.Mask" "B.Paste")
			(net "NetC4_2")
			(solder_mask_margin 0.05)
			(solder_paste_margin 0)
		)
		(pad "2" smd rect
			(at 0.48 0 180)
			(size 0.57 0.62)
			(layers "B.Cu" "B.Mask" "B.Paste")
			(net "GND")
			(solder_mask_margin 0.05)
			(solder_paste_margin 0)
		)
	)
	(footprint "Vault:RESC1005X040N"
		(layer "B.Cu")
		(at 142.546105 106.178605)
		(property "Reference" "R2"
			(at -2.32 -0.12517 0)
			(unlocked yes)
			(layer "B.SilkS")
			(effects
				(font
					(face "Arial")
					(size 0.63 0.63)
					(thickness 0.254)
				)
				(justify mirror)
			)
		)
		(property "Value" "Yageo_RC0402FR-0791KL"
			(at -9.98758 12.23942 0)
			(unlocked yes)
			(layer "B.SilkS")
			(hide yes)
			(effects
				(font
					(face "Arial")
					(size 0.63 0.63)
					(thickness 0.254)
				)
				(justify mirror)
			)
		)
		(sheetname "SCH_SA45_DaughterCard")
		(sheetfile "SCH_SA45_DaughterCard.kicad_sch")
		(duplicate_pad_numbers_are_jumpers no)
		(fp_line
			(start -0.95 -0.5)
			(end 0.95 -0.5)
			(stroke
				(width 0.1)
				(type solid)
			)
			(layer "B.CrtYd")
		)
		(fp_line
			(start -0.95 0.5)
			(end -0.95 -0.5)
			(stroke
				(width 0.1)
				(type solid)
			)
			(layer "B.CrtYd")
		)
		(fp_line
			(start -0.95 0.5)
			(end 0.95 0.5)
			(stroke
				(width 0.1)
				(type solid)
			)
			(layer "B.CrtYd")
		)
		(fp_line
			(start 0.95 0.5)
			(end 0.95 -0.5)
			(stroke
				(width 0.1)
				(type solid)
			)
			(layer "B.CrtYd")
		)
		(fp_line
			(start -0.5 -0.25)
			(end 0.5 -0.25)
			(stroke
				(width 0.05)
				(type solid)
			)
			(layer "B.Fab")
		)
		(fp_line
			(start -0.5 0.25)
			(end -0.5 -0.25)
			(stroke
				(width 0.05)
				(type solid)
			)
			(layer "B.Fab")
		)
		(fp_line
			(start -0.5 0.25)
			(end 0.5 0.25)
			(stroke
				(width 0.05)
				(type solid)
			)
			(layer "B.Fab")
		)
		(fp_line
			(start 0.5 0.25)
			(end 0.5 -0.25)
			(stroke
				(width 0.05)
				(type solid)
			)
			(layer "B.Fab")
		)
		(fp_text_box "${REFERENCE}"
			(start -1.09004 -0.20727)
			(end 1.09004 0.20726)
			(margins 0 0 0 0)
			(layer "B.Fab")
			(effects
				(font
					(face "Arial")
					(size 0.315 0.315)
					(thickness 0.254)
				)
				(justify top mirror)
			)
			(border no)
			(stroke
				(width 0.1)
				(type default)
			)
			(knockout no)
		)
		(pad "1" smd rect
			(at -0.48 0)
			(size 0.57 0.62)
			(layers "B.Cu" "B.Mask" "B.Paste")
			(net "+3.3V")
			(solder_mask_margin 0.05)
			(solder_paste_margin 0)
		)
		(pad "2" smd rect
			(at 0.48 0)
			(size 0.57 0.62)
			(layers "B.Cu" "B.Mask" "B.Paste")
			(net "NetC4_2")
			(solder_mask_margin 0.05)
			(solder_paste_margin 0)
		)
	)
	(footprint "Vault:TH001V_109DIA_000mt_8600-0"
		(layer "B.Cu")
		(at 130.239105 81.993605 180)
		(property "Reference" "P6"
			(at 0.000005 1.68071 0)
			(unlocked yes)
			(layer "B.SilkS")
			(effects
				(font
					(face "Arial")
					(size 0.63 0.63)
					(thickness 0.254)
				)
				(justify mirror)
			)
		)
		(property "Value" "Mill-Max_8600-0-05-80-00-00-03-0"
			(at 22.534825 -2.89778 0)
			(unlocked yes)
			(layer "B.SilkS")
			(hide yes)
			(effects
				(font
					(face "Arial")
					(size 0.63 0.63)
					(thickness 0.254)
				)
				(justify mirror)
			)
		)
		(sheetname "SCH_SA45_DaughterCard")
		(sheetfile "SCH_SA45_DaughterCard.kicad_sch")
		(duplicate_pad_numbers_are_jumpers no)
		(fp_line
			(start 1.4 1.4)
			(end -1.4 1.4)
			(stroke
				(width 0.1)
				(type solid)
			)
			(layer "B.CrtYd")
		)
		(fp_line
			(start 1.4 -1.4)
			(end 1.4 1.4)
			(stroke
				(width 0.1)
				(type solid)
			)
			(layer "B.CrtYd")
		)
		(fp_line
			(start 1.4 -1.4)
			(end -1.4 -1.4)
			(stroke
				(width 0.1)
				(type solid)
			)
			(layer "B.CrtYd")
		)
		(fp_line
			(start -1.4 -1.4)
			(end -1.4 1.4)
			(stroke
				(width 0.1)
				(type solid)
			)
			(layer "B.CrtYd")
		)
		(fp_circle
			(center 0 0)
			(end 0 0.545)
			(stroke
				(width 0.1)
				(type solid)
			)
			(fill no)
			(layer "B.Fab")
		)
		(fp_text user "${REFERENCE}"
			(at 0 0.166251 360)
			(unlocked yes)
			(layer "B.Fab")
			(effects
				(font
					(face "Arial")
					(size 0.8001 0.8001)
					(thickness 0.254)
				)
				(justify mirror)
			)
		)
		(pad "1" thru_hole circle
			(at 0 -0.02 180)
			(size 2.09 2.09)
			(drill 1.09)
			(layers "*.Cu" "*.Mask")
			(remove_unused_layers no)
			(net "LOCK")
			(solder_mask_margin 0.05)
			(solder_paste_margin -2147.48364)
			(thermal_bridge_angle 90)
		)
	)
	(footprint "Vault:RESC0603X026N"
		(layer "B.Cu")
		(at 144.026105 104.788605 90)
		(property "Reference" "R6"
			(at 3.41026 -0.210005 0)
			(unlocked yes)
			(layer "B.SilkS")
			(effects
				(font
					(face "Arial")
					(size 0.63 0.63)
					(thickness 0.254)
				)
				(justify mirror)
			)
		)
		(property "Value" "Yageo_RC0201JR-070RL"
			(at -12.38782 -12.63902 0)
			(unlocked yes)
			(layer "B.SilkS")
			(hide yes)
			(effects
				(font
					(face "Arial")
					(size 0.63 0.63)
					(thickness 0.254)
				)
				(justify mirror)
			)
		)
		(sheetname "SCH_SA45_DaughterCard")
		(sheetfile "SCH_SA45_DaughterCard.kicad_sch")
		(duplicate_pad_numbers_are_jumpers no)
		(fp_line
			(start 0.75 -0.4)
			(end 0.75 0.4)
			(stroke
				(width 0.1)
				(type solid)
			)
			(layer "B.CrtYd")
		)
		(fp_line
			(start -0.75 -0.4)
			(end 0.75 -0.4)
			(stroke
				(width 0.1)
				(type solid)
			)
			(layer "B.CrtYd")
		)
		(fp_line
			(start -0.75 -0.4)
			(end -0.75 0.4)
			(stroke
				(width 0.1)
				(type solid)
			)
			(layer "B.CrtYd")
		)
		(fp_line
			(start -0.75 0.4)
			(end 0.75 0.4)
			(stroke
				(width 0.1)
				(type solid)
			)
			(layer "B.CrtYd")
		)
		(fp_line
			(start 0.3 -0.15)
			(end 0.3 0.15)
			(stroke
				(width 0.05)
				(type solid)
			)
			(layer "B.Fab")
		)
		(fp_line
			(start -0.3 -0.15)
			(end 0.3 -0.15)
			(stroke
				(width 0.05)
				(type solid)
			)
			(layer "B.Fab")
		)
		(fp_line
			(start -0.3 -0.15)
			(end -0.3 0.15)
			(stroke
				(width 0.05)
				(type solid)
			)
			(layer "B.Fab")
		)
		(fp_line
			(start -0.3 0.15)
			(end 0.3 0.15)
			(stroke
				(width 0.05)
				(type solid)
			)
			(layer "B.Fab")
		)
		(fp_text_box "${REFERENCE}"
			(start 0.20727 -1.09004)
			(end -0.20726 1.09004)
			(margins 0 0 0 0)
			(angle -90)
			(layer "B.Fab")
			(effects
				(font
					(face "Arial")
					(size 0.315 0.315)
					(thickness 0.254)
				)
				(justify top mirror)
			)
			(border no)
			(stroke
				(width 0.1)
				(type default)
			)
			(knockout no)
		)
		(pad "1" smd rect
			(at -0.34 0 90)
			(size 0.44 0.42)
			(layers "B.Cu" "B.Mask" "B.Paste")
			(net "NetR5_1")
			(solder_mask_margin 0.05)
			(solder_paste_margin 0)
		)
		(pad "2" smd rect
			(at 0.34 0 90)
			(size 0.44 0.42)
			(layers "B.Cu" "B.Mask" "B.Paste")
			(net "GND")
			(solder_mask_margin 0.05)
			(solder_paste_margin 0)
		)
	)
	(footprint "Vault:CAPC2013X140N"
		(layer "B.Cu")
		(at 151.476105 117.553605 180)
		(property "Reference" "C11"
			(at -2.95163 0.12656 0)
			(unlocked yes)
			(layer "B.SilkS")
			(effects
				(font
					(face "Arial")
					(size 0.63 0.63)
					(thickness 0.254)
				)
				(justify mirror)
			)
		)
		(property "Value" "Murata_GRM21BR61A226ME51L"
			(at 19.40959 6.33785 0)
			(unlocked yes)
			(layer "B.SilkS")
			(hide yes)
			(effects
				(font
					(face "Arial")
					(size 0.63 0.63)
					(thickness 0.254)
				)
				(justify mirror)
			)
		)
		(sheetname "SCH_SA45_DaughterCard")
		(sheetfile "SCH_SA45_DaughterCard.kicad_sch")
		(duplicate_pad_numbers_are_jumpers no)
		(fp_line
			(start 1.8 1.1)
			(end -1.8 1.1)
			(stroke
				(width 0.1)
				(type solid)
			)
			(layer "B.CrtYd")
		)
		(fp_line
			(start 1.8 -1.1)
			(end 1.8 1.1)
			(stroke
				(width 0.1)
				(type solid)
			)
			(layer "B.CrtYd")
		)
		(fp_line
			(start 1.8 -1.1)
			(end -1.8 -1.1)
			(stroke
				(width 0.1)
				(type solid)
			)
			(layer "B.CrtYd")
		)
		(fp_line
			(start -1.8 -1.1)
			(end -1.8 1.1)
			(stroke
				(width 0.1)
				(type solid)
			)
			(layer "B.CrtYd")
		)
		(fp_line
			(start 1 0.65)
			(end -1 0.65)
			(stroke
				(width 0.05)
				(type solid)
			)
			(layer "B.Fab")
		)
		(fp_line
			(start 1 -0.65)
			(end 1 0.65)
			(stroke
				(width 0.05)
				(type solid)
			)
			(layer "B.Fab")
		)
		(fp_line
			(start 1 -0.65)
			(end -1 -0.65)
			(stroke
				(width 0.05)
				(type solid)
			)
			(layer "B.Fab")
		)
		(fp_line
			(start -1 -0.65)
			(end -1 0.65)
			(stroke
				(width 0.05)
				(type solid)
			)
			(layer "B.Fab")
		)
		(fp_text_box "${REFERENCE}"
			(start 1.09004 0.20729)
			(end -1.09004 -0.20729)
			(margins 0 0 0 0)
			(angle -180)
			(layer "B.Fab")
			(effects
				(font
					(face "Arial")
					(size 0.315 0.315)
					(thickness 0.254)
				)
				(justify top mirror)
			)
			(border no)
			(stroke
				(width 0.1)
				(type default)
			)
			(knockout no)
		)
		(pad "1" smd rect
			(at -0.9 0 180)
			(size 1.3 1.65)
			(layers "B.Cu" "B.Mask" "B.Paste")
			(net "+3.3V")
			(solder_mask_margin 0.05)
			(solder_paste_margin 0)
		)
		(pad "2" smd rect
			(at 0.9 0 180)
			(size 1.3 1.65)
			(layers "B.Cu" "B.Mask" "B.Paste")
			(net "GND")
			(solder_mask_margin 0.05)
			(solder_paste_margin 0)
		)
	)
	(footprint "Vault:RESC3216X070N"
		(layer "B.Cu")
		(at 161.901105 117.703605)
		(property "Reference" "R3"
			(at 0.000005 -2.12071 0)
			(unlocked yes)
			(layer "B.SilkS")
			(effects
				(font
					(face "Arial")
					(size 0.63 0.63)
					(thickness 0.254)
				)
				(justify mirror)
			)
		)
		(property "Value" "Yageo_RC1206JR-070RL"
			(at 4.77019 0.63171 0)
			(unlocked yes)
			(layer "B.SilkS")
			(hide yes)
			(effects
				(font
					(face "Arial")
					(size 0.63 0.63)
					(thickness 0.254)
				)
				(justify mirror)
			)
		)
		(sheetname "SCH_SA45_DaughterCard")
		(sheetfile "SCH_SA45_DaughterCard.kicad_sch")
		(duplicate_pad_numbers_are_jumpers no)
		(fp_line
			(start -0.7 -0.9)
			(end 0.7 -0.9)
			(stroke
				(width 0.1)
				(type solid)
			)
			(layer "B.SilkS")
		)
		(fp_line
			(start -0.7 0.9)
			(end 0.7 0.9)
			(stroke
				(width 0.1)
				(type solid)
			)
			(layer "B.SilkS")
		)
		(fp_line
			(start -2.3 -1.15)
			(end 2.3 -1.15)
			(stroke
				(width 0.1)
				(type solid)
			)
			(layer "B.CrtYd")
		)
		(fp_line
			(start -2.3 1.15)
			(end -2.3 -1.15)
			(stroke
				(width 0.1)
				(type solid)
			)
			(layer "B.CrtYd")
		)
		(fp_line
			(start -2.3 1.15)
			(end 2.3 1.15)
			(stroke
				(width 0.1)
				(type solid)
			)
			(layer "B.CrtYd")
		)
		(fp_line
			(start 2.3 1.15)
			(end 2.3 -1.15)
			(stroke
				(width 0.1)
				(type solid)
			)
			(layer "B.CrtYd")
		)
		(fp_line
			(start -1.6 -0.8)
			(end 1.6 -0.8)
			(stroke
				(width 0.05)
				(type solid)
			)
			(layer "B.Fab")
		)
		(fp_line
			(start -1.6 0.8)
			(end -1.6 -0.8)
			(stroke
				(width 0.05)
				(type solid)
			)
			(layer "B.Fab")
		)
		(fp_line
			(start -1.6 0.8)
			(end 1.6 0.8)
			(stroke
				(width 0.05)
				(type solid)
			)
			(layer "B.Fab")
		)
		(fp_line
			(start 1.6 0.8)
			(end 1.6 -0.8)
			(stroke
				(width 0.05)
				(type solid)
			)
			(layer "B.Fab")
		)
		(fp_text_box "${REFERENCE}"
			(start 1.14717 0.20754)
			(end -1.14713 -0.20759)
			(margins 0 0 0 0)
			(angle 180)
			(layer "B.Fab")
			(effects
				(font
					(face "Arial")
					(size 0.315 0.315)
					(thickness 0.254)
				)
				(justify top mirror)
			)
			(border no)
			(stroke
				(width 0.1)
				(type default)
			)
			(knockout no)
		)
		(pad "1" smd rect
			(at -1.5 0)
			(size 1.05 1.75)
			(layers "B.Cu" "B.Mask" "B.Paste")
			(net "+3.3V")
			(solder_mask_margin 0.05)
			(solder_paste_margin 0)
		)
		(pad "2" smd rect
			(at 1.5 0)
			(size 1.05 1.75)
			(layers "B.Cu" "B.Mask" "B.Paste")
			(net "+3.3V_OSC")
			(solder_mask_margin 0.05)
			(solder_paste_margin 0)
		)
	)
	(footprint "Vault:TH001V_109DIA_000mt_8600-0"
		(layer "B.Cu")
		(at 168.841105 105.003605 180)
		(property "Reference" "P2"
			(at 0 2.11291 0)
			(unlocked yes)
			(layer "B.SilkS")
			(effects
				(font
					(face "Arial")
					(size 0.63 0.63)
					(thickness 0.254)
				)
				(justify mirror)
			)
		)
		(property "Value" "Mill-Max_8600-0-05-80-00-00-03-0"
			(at 22.534825 -2.89778 0)
			(unlocked yes)
			(layer "B.SilkS")
			(hide yes)
			(effects
				(font
					(face "Arial")
					(size 0.63 0.63)
					(thickness 0.254)
				)
				(justify mirror)
			)
		)
		(sheetname "SCH_SA45_DaughterCard")
		(sheetfile "SCH_SA45_DaughterCard.kicad_sch")
		(duplicate_pad_numbers_are_jumpers no)
		(fp_line
			(start 1.4 1.4)
			(end -1.4 1.4)
			(stroke
				(width 0.1)
				(type solid)
			)
			(layer "B.CrtYd")
		)
		(fp_line
			(start 1.4 -1.4)
			(end 1.4 1.4)
			(stroke
				(width 0.1)
				(type solid)
			)
			(layer "B.CrtYd")
		)
		(fp_line
			(start 1.4 -1.4)
			(end -1.4 -1.4)
			(stroke
				(width 0.1)
				(type solid)
			)
			(layer "B.CrtYd")
		)
		(fp_line
			(start -1.4 -1.4)
			(end -1.4 1.4)
			(stroke
				(width 0.1)
				(type solid)
			)
			(layer "B.CrtYd")
		)
		(fp_circle
			(center 0 0)
			(end 0 0.545)
			(stroke
				(width 0.1)
				(type solid)
			)
			(fill no)
			(layer "B.Fab")
		)
		(fp_text user "${REFERENCE}"
			(at 0.000005 0.159211 360)
			(unlocked yes)
			(layer "B.Fab")
			(effects
				(font
					(face "Arial")
					(size 0.8001 0.8001)
					(thickness 0.254)
				)
				(justify mirror)
			)
		)
		(pad "1" thru_hole circle
			(at 0 0 180)
			(size 2.09 2.09)
			(drill 1.09)
			(layers "*.Cu" "*.Mask")
			(remove_unused_layers no)
			(net "GND")
			(solder_mask_margin 0.05)
			(solder_paste_margin -2147.48364)
			(thermal_bridge_angle 90)
		)
	)
	(footprint "Vault:TH001V_109DIA_000mt_8600-0"
		(layer "B.Cu")
		(at 133.287105 81.993605 180)
		(property "Reference" "P7"
			(at 0.000005 1.67655 0)
			(unlocked yes)
			(layer "B.SilkS")
			(effects
				(font
					(face "Arial")
					(size 0.63 0.63)
					(thickness 0.254)
				)
				(justify mirror)
			)
		)
		(property "Value" "Mill-Max_8600-0-05-80-00-00-03-0"
			(at 22.534825 -2.89778 0)
			(unlocked yes)
			(layer "B.SilkS")
			(hide yes)
			(effects
				(font
					(face "Arial")
					(size 0.63 0.63)
					(thickness 0.254)
				)
				(justify mirror)
			)
		)
		(sheetname "SCH_SA45_DaughterCard")
		(sheetfile "SCH_SA45_DaughterCard.kicad_sch")
		(duplicate_pad_numbers_are_jumpers no)
		(fp_line
			(start 1.4 1.4)
			(end -1.4 1.4)
			(stroke
				(width 0.1)
				(type solid)
			)
			(layer "B.CrtYd")
		)
		(fp_line
			(start 1.4 -1.4)
			(end 1.4 1.4)
			(stroke
				(width 0.1)
				(type solid)
			)
			(layer "B.CrtYd")
		)
		(fp_line
			(start 1.4 -1.4)
			(end -1.4 -1.4)
			(stroke
				(width 0.1)
				(type solid)
			)
			(layer "B.CrtYd")
		)
		(fp_line
			(start -1.4 -1.4)
			(end -1.4 1.4)
			(stroke
				(width 0.1)
				(type solid)
			)
			(layer "B.CrtYd")
		)
		(fp_circle
			(center 0 0)
			(end 0 0.545)
			(stroke
				(width 0.1)
				(type solid)
			)
			(fill no)
			(layer "B.Fab")
		)
		(fp_text user "${REFERENCE}"
			(at 0 0.160971 360)
			(unlocked yes)
			(layer "B.Fab")
			(effects
				(font
					(face "Arial")
					(size 0.8001 0.8001)
					(thickness 0.254)
				)
				(justify mirror)
			)
		)
		(pad "1" thru_hole circle
			(at 0 -0.02 180)
			(size 2.09 2.09)
			(drill 1.09)
			(layers "*.Cu" "*.Mask")
			(remove_unused_layers no)
			(net "TX")
			(solder_mask_margin 0.05)
			(solder_paste_margin -2147.48364)
			(thermal_bridge_angle 90)
		)
	)
	(footprint "Vault:CAPC2013X145N"
		(layer "B.Cu")
		(at 144.976105 112.953605)
		(property "Reference" "C7"
			(at -2.69615 -0.12655 0)
			(unlocked yes)
			(layer "B.SilkS")
			(effects
				(font
					(face "Arial")
					(size 0.63 0.63)
					(thickness 0.254)
				)
				(justify mirror)
			)
		)
		(property "Value" "Murata_GRM21BR6YA106KE43L"
			(at -8.17338 -1.49206 0)
			(unlocked yes)
			(layer "B.SilkS")
			(hide yes)
			(effects
				(font
					(face "Arial")
					(size 0.63 0.63)
					(thickness 0.254)
				)
				(justify mirror)
			)
		)
		(sheetname "SCH_SA45_DaughterCard")
		(sheetfile "SCH_SA45_DaughterCard.kicad_sch")
		(duplicate_pad_numbers_are_jumpers no)
		(fp_line
			(start -1.8 -1.1)
			(end 1.8 -1.1)
			(stroke
				(width 0.1)
				(type solid)
			)
			(layer "B.CrtYd")
		)
		(fp_line
			(start -1.8 1.1)
			(end -1.8 -1.1)
			(stroke
				(width 0.1)
				(type solid)
			)
			(layer "B.CrtYd")
		)
		(fp_line
			(start -1.8 1.1)
			(end 1.8 1.1)
			(stroke
				(width 0.1)
				(type solid)
			)
			(layer "B.CrtYd")
		)
		(fp_line
			(start 1.8 1.1)
			(end 1.8 -1.1)
			(stroke
				(width 0.1)
				(type solid)
			)
			(layer "B.CrtYd")
		)
		(fp_line
			(start -1 -0.65001)
			(end 1 -0.65001)
			(stroke
				(width 0.05)
				(type solid)
			)
			(layer "B.Fab")
		)
		(fp_line
			(start -1 0.65)
			(end -1 -0.65001)
			(stroke
				(width 0.05)
				(type solid)
			)
			(layer "B.Fab")
		)
		(fp_line
			(start -1 0.65)
			(end 1 0.65)
			(stroke
				(width 0.05)
				(type solid)
			)
			(layer "B.Fab")
		)
		(fp_line
			(start 1 0.65)
			(end 1 -0.65001)
			(stroke
				(width 0.05)
				(type solid)
			)
			(layer "B.Fab")
		)
		(fp_text_box "${REFERENCE}"
			(start 1.14717 0.20756)
			(end -1.14713 -0.20757)
			(margins 0 0 0 0)
			(angle 180)
			(layer "B.Fab")
			(effects
				(font
					(face "Arial")
					(size 0.315 0.315)
					(thickness 0.254)
				)
				(justify top mirror)
			)
			(border no)
			(stroke
				(width 0.1)
				(type default)
			)
			(knockout no)
		)
		(pad "1" smd rect
			(at -0.9 0)
			(size 1.3 1.65)
			(layers "B.Cu" "B.Mask" "B.Paste")
			(net "+5V")
			(solder_mask_margin 0.05)
			(solder_paste_margin 0)
		)
		(pad "2" smd rect
			(at 0.9 0)
			(size 1.3 1.65)
			(layers "B.Cu" "B.Mask" "B.Paste")
			(net "GND")
			(solder_mask_margin 0.05)
			(solder_paste_margin 0)
		)
	)
	(footprint "FAB_SA45_DaughterCard:Keystone_4871"
		(locked yes)
		(layer "B.Cu")
		(at 163.661105 126.343605 180)
		(property "Reference" "J4"
			(at -0.00185 4.4071 0)
			(unlocked yes)
			(layer "B.SilkS")
			(effects
				(font
					(face "Arial")
					(size 0.63 0.63)
					(thickness 0.254)
				)
				(justify mirror)
			)
		)
		(property "Value" "Keystone_4871"
			(at 6.3343 -5.019802 0)
			(unlocked yes)
			(layer "B.SilkS")
			(hide yes)
			(effects
				(font
					(size 1.524 1.524)
					(thickness 0.254)
				)
				(justify mirror)
			)
		)
		(sheetname "SCH_SA45_DaughterCard")
		(sheetfile "SCH_SA45_DaughterCard.kicad_sch")
		(duplicate_pad_numbers_are_jumpers no)
		(fp_line
			(start 3.4 3.4)
			(end -3.4 3.4)
			(stroke
				(width 0.1)
				(type solid)
			)
			(layer "B.CrtYd")
		)
		(fp_line
			(start 3.4 -3.4)
			(end 3.4 3.4)
			(stroke
				(width 0.1)
				(type solid)
			)
			(layer "B.CrtYd")
		)
		(fp_line
			(start 3.4 -3.4)
			(end -3.4 -3.4)
			(stroke
				(width 0.1)
				(type solid)
			)
			(layer "B.CrtYd")
		)
		(fp_line
			(start -3.4 -0.8)
			(end -3.4 3.4)
			(stroke
				(width 0.1)
				(type solid)
			)
			(layer "B.CrtYd")
		)
		(fp_line
			(start -3.4 -3.4)
			(end -3.4 -0.8)
			(stroke
				(width 0.1)
				(type solid)
			)
			(layer "B.CrtYd")
		)
		(fp_text user ""
			(at 0.367795 0.63446 360)
			(unlocked yes)
			(layer "B.Fab")
			(effects
				(font
					(face "Arial")
					(size 0.63 0.63)
					(thickness 0.254)
				)
				(justify mirror)
			)
		)
		(fp_text user "${REFERENCE}"
			(at -0.00185 0.20085 360)
			(unlocked yes)
			(layer "B.Fab")
			(effects
				(font
					(face "Arial")
					(size 0.63 0.63)
					(thickness 0.254)
				)
				(justify mirror)
			)
		)
		(pad "Hole" thru_hole circle
			(at 0 0 180)
			(size 0 0)
			(drill 3.7)
			(layers "*.Cu" "*.Mask")
			(remove_unused_layers no)
			(thermal_bridge_angle 90)
		)
		(pad "MT" smd circle
			(at 0 0 180)
			(size 6.2 6.2)
			(layers "B.Cu" "B.Mask" "B.Paste")
			(solder_mask_margin 0.05)
			(thermal_bridge_angle 90)
		)
	)
	(footprint "Vault:TH001V_109DIA_000mt_8600-0"
		(layer "B.Cu")
		(at 139.383105 81.993605 180)
		(property "Reference" "P9"
			(at 0 -1.90429 0)
			(unlocked yes)
			(layer "B.SilkS")
			(effects
				(font
					(face "Arial")
					(size 0.63 0.63)
					(thickness 0.254)
				)
				(justify mirror)
			)
		)
		(property "Value" "Mill-Max_8600-0-05-80-00-00-03-0"
			(at 22.534825 -2.89778 0)
			(unlocked yes)
			(layer "B.SilkS")
			(hide yes)
			(effects
				(font
					(face "Arial")
					(size 0.63 0.63)
					(thickness 0.254)
				)
				(justify mirror)
			)
		)
		(sheetname "SCH_SA45_DaughterCard")
		(sheetfile "SCH_SA45_DaughterCard.kicad_sch")
		(duplicate_pad_numbers_are_jumpers no)
		(fp_line
			(start 1.4 1.4)
			(end -1.4 1.4)
			(stroke
				(width 0.1)
				(type solid)
			)
			(layer "B.CrtYd")
		)
		(fp_line
			(start 1.4 -1.4)
			(end 1.4 1.4)
			(stroke
				(width 0.1)
				(type solid)
			)
			(layer "B.CrtYd")
		)
		(fp_line
			(start 1.4 -1.4)
			(end -1.4 -1.4)
			(stroke
				(width 0.1)
				(type solid)
			)
			(layer "B.CrtYd")
		)
		(fp_line
			(start -1.4 -1.4)
			(end -1.4 1.4)
			(stroke
				(width 0.1)
				(type solid)
			)
			(layer "B.CrtYd")
		)
		(fp_circle
			(center 0 0)
			(end 0 0.545)
			(stroke
				(width 0.1)
				(type solid)
			)
			(fill no)
			(layer "B.Fab")
		)
		(fp_text user "${REFERENCE}"
			(at 0 0.166251 360)
			(unlocked yes)
			(layer "B.Fab")
			(effects
				(font
					(face "Arial")
					(size 0.8001 0.8001)
					(thickness 0.254)
				)
				(justify mirror)
			)
		)
		(pad "1" thru_hole circle
			(at 0 -0.02 180)
			(size 2.09 2.09)
			(drill 1.09)
			(layers "*.Cu" "*.Mask")
			(remove_unused_layers no)
			(net "1PPS_IN")
			(solder_mask_margin 0.05)
			(solder_paste_margin -2147.48364)
			(thermal_bridge_angle 90)
		)
	)
	(footprint "Vault:TH001V_109DIA_000mt_8600-0"
		(layer "B.Cu")
		(at 168.841105 84.663605 180)
		(property "Reference" "P3"
			(at -0.000005 2.21571 0)
			(unlocked yes)
			(layer "B.SilkS")
			(effects
				(font
					(face "Arial")
					(size 0.63 0.63)
					(thickness 0.254)
				)
				(justify mirror)
			)
		)
		(property "Value" "Mill-Max_8600-0-05-80-00-00-03-0"
			(at 22.534825 -2.89778 0)
			(unlocked yes)
			(layer "B.SilkS")
			(hide yes)
			(effects
				(font
					(face "Arial")
					(size 0.63 0.63)
					(thickness 0.254)
				)
				(justify mirror)
			)
		)
		(sheetname "SCH_SA45_DaughterCard")
		(sheetfile "SCH_SA45_DaughterCard.kicad_sch")
		(duplicate_pad_numbers_are_jumpers no)
		(fp_line
			(start 1.4 1.4)
			(end -1.4 1.4)
			(stroke
				(width 0.1)
				(type solid)
			)
			(layer "B.CrtYd")
		)
		(fp_line
			(start 1.4 -1.4)
			(end 1.4 1.4)
			(stroke
				(width 0.1)
				(type solid)
			)
			(layer "B.CrtYd")
		)
		(fp_line
			(start 1.4 -1.4)
			(end -1.4 -1.4)
			(stroke
				(width 0.1)
				(type solid)
			)
			(layer "B.CrtYd")
		)
		(fp_line
			(start -1.4 -1.4)
			(end -1.4 1.4)
			(stroke
				(width 0.1)
				(type solid)
			)
			(layer "B.CrtYd")
		)
		(fp_circle
			(center 0 0)
			(end 0 0.545)
			(stroke
				(width 0.1)
				(type solid)
			)
			(fill no)
			(layer "B.Fab")
		)
		(fp_text user "${REFERENCE}"
			(at 0 0.166251 360)
			(unlocked yes)
			(layer "B.Fab")
			(effects
				(font
					(face "Arial")
					(size 0.8001 0.8001)
					(thickness 0.254)
				)
				(justify mirror)
			)
		)
		(pad "1" thru_hole circle
			(at 0.04 -0.04 180)
			(size 2.09 2.09)
			(drill 1.09)
			(layers "*.Cu" "*.Mask")
			(remove_unused_layers no)
			(net "RF_OUTPUT")
			(solder_mask_margin 0.05)
			(solder_paste_margin -2147.48364)
			(thermal_bridge_angle 90)
		)
	)
	(footprint "Vault:CAPC1005X055N"
		(layer "B.Cu")
		(at 168.251105 117.243605 90)
		(property "Reference" "C2"
			(at 0.12655 1.449995 0)
			(unlocked yes)
			(layer "B.SilkS")
			(effects
				(font
					(face "Arial")
					(size 0.63 0.63)
					(thickness 0.254)
				)
				(justify mirror)
			)
		)
		(property "Value" "Murata_GRM155R61H104KE14D"
			(at -5.85071 -11.085985 0)
			(unlocked yes)
			(layer "B.SilkS")
			(hide yes)
			(effects
				(font
					(face "Arial")
					(size 0.63 0.63)
					(thickness 0.254)
				)
				(justify mirror)
			)
		)
		(sheetname "SCH_SA45_DaughterCard")
		(sheetfile "SCH_SA45_DaughterCard.kicad_sch")
		(duplicate_pad_numbers_are_jumpers no)
		(fp_line
			(start 0.95 -0.5)
			(end 0.95 0.5)
			(stroke
				(width 0.1)
				(type solid)
			)
			(layer "B.CrtYd")
		)
		(fp_line
			(start -0.95 -0.5)
			(end 0.95 -0.5)
			(stroke
				(width 0.1)
				(type solid)
			)
			(layer "B.CrtYd")
		)
		(fp_line
			(start -0.95 -0.5)
			(end -0.95 0.5)
			(stroke
				(width 0.1)
				(type solid)
			)
			(layer "B.CrtYd")
		)
		(fp_line
			(start -0.95 0.5)
			(end 0.95 0.5)
			(stroke
				(width 0.1)
				(type solid)
			)
			(layer "B.CrtYd")
		)
		(fp_line
			(start 0.5 -0.25)
			(end 0.5 0.25)
			(stroke
				(width 0.05)
				(type solid)
			)
			(layer "B.Fab")
		)
		(fp_line
			(start -0.5 -0.25)
			(end 0.5 -0.25)
			(stroke
				(width 0.05)
				(type solid)
			)
			(layer "B.Fab")
		)
		(fp_line
			(start -0.5 -0.25)
			(end -0.5 0.25)
			(stroke
				(width 0.05)
				(type solid)
			)
			(layer "B.Fab")
		)
		(fp_line
			(start -0.5 0.25)
			(end 0.5 0.25)
			(stroke
				(width 0.05)
				(type solid)
			)
			(layer "B.Fab")
		)
		(fp_text_box "${REFERENCE}"
			(start 1.14716 0.20757)
			(end -1.14714 -0.20756)
			(margins 0 0 0 0)
			(angle 180)
			(layer "B.Fab")
			(effects
				(font
					(face "Arial")
					(size 0.315 0.315)
					(thickness 0.254)
				)
				(justify top mirror)
			)
			(border no)
			(stroke
				(width 0.1)
				(type default)
			)
			(knockout no)
		)
		(pad "1" smd rect
			(at -0.46 0 90)
			(size 0.6 0.62)
			(layers "B.Cu" "B.Mask" "B.Paste")
			(net "+3.3V_OSC")
			(solder_mask_margin 0.05)
			(solder_paste_margin 0)
		)
		(pad "2" smd rect
			(at 0.46 0 90)
			(size 0.6 0.62)
			(layers "B.Cu" "B.Mask" "B.Paste")
			(net "GND")
			(solder_mask_margin 0.05)
			(solder_paste_margin 0)
		)
	)
	(footprint "Vault:FID_1p0mm"
		(layer "B.Cu")
		(at 171.276105 81.828605 180)
		(property "Reference" "Designator6"
			(at 7.084135 3.019298 0)
			(unlocked yes)
			(layer "B.SilkS")
			(hide yes)
			(effects
				(font
					(size 1.524 1.524)
					(thickness 0.254)
				)
				(justify mirror)
			)
		)
		(property "Value" "Comment"
			(at 5.07844 0.707898 0)
			(unlocked yes)
			(layer "B.SilkS")
			(hide yes)
			(effects
				(font
					(size 1.524 1.524)
					(thickness 0.254)
				)
				(justify mirror)
			)
		)
		(sheetfile ".kicad_sch")
		(duplicate_pad_numbers_are_jumpers no)
		(fp_circle
			(center 0 0)
			(end 0 1)
			(stroke
				(width 0.1)
				(type solid)
			)
			(fill no)
			(layer "B.CrtYd")
		)
		(pad "1" smd circle
			(at 0 0 90)
			(size 1 1)
			(layers "B.Cu" "B.Mask" "B.Paste")
			(solder_mask_margin 0.5)
			(solder_paste_margin -6)
			(thermal_bridge_angle 90)
		)
		(zone
			(layer "B.Cu")
			(hatch edge 0.5)
			(connect_pads
				(clearance 0)
			)
			(min_thickness 0.25)
			(keepout
				(tracks not_allowed)
				(vias not_allowed)
				(pads allowed)
				(copperpour not_allowed)
				(footprints allowed)
			)
			(placement
				(enabled no)
				(sheetname "")
			)
			(fill
				(thermal_gap 0.5)
				(thermal_bridge_width 0.5)
				(island_removal_mode 0)
			)
			(polygon
				(pts
					(xy 171.56639 80.871665) (xy 171.747502 80.946684) (xy 171.910498 81.055595) (xy 172.049115 81.194212)
					(xy 172.158026 81.357208) (xy 172.233045 81.53832) (xy 172.27129 81.730588) (xy 172.27129 81.926622)
					(xy 172.233045 82.11889) (xy 172.158026 82.300002) (xy 172.049115 82.462998) (xy 171.910498 82.601615)
					(xy 171.747502 82.710526) (xy 171.56639 82.785545) (xy 171.374122 82.82379) (xy 171.178088 82.82379)
					(xy 170.98582 82.785545) (xy 170.804708 82.710526) (xy 170.641712 82.601615) (xy 170.503095 82.462998)
					(xy 170.394184 82.300002) (xy 170.319165 82.11889) (xy 170.28092 81.926622) (xy 170.28092 81.762779)
					(xy 170.776105 81.762779) (xy 170.776105 81.894431) (xy 170.81018 82.021598) (xy 170.876006 82.135612)
					(xy 170.969098 82.228704) (xy 171.083112 82.29453) (xy 171.210279 82.328605) (xy 171.341931 82.328605)
					(xy 171.469098 82.29453) (xy 171.583112 82.228704) (xy 171.676204 82.135612) (xy 171.74203 82.021598)
					(xy 171.776105 81.894431) (xy 171.776105 81.762779) (xy 171.74203 81.635612) (xy 171.676204 81.521598)
					(xy 171.583112 81.428506) (xy 171.469098 81.36268) (xy 171.341931 81.328605) (xy 171.210279 81.328605)
					(xy 171.083112 81.36268) (xy 170.969098 81.428506) (xy 170.876006 81.521598) (xy 170.81018 81.635612)
					(xy 170.776105 81.762779) (xy 170.28092 81.762779) (xy 170.28092 81.730588) (xy 170.319165 81.53832)
					(xy 170.394184 81.357208) (xy 170.503095 81.194212) (xy 170.641712 81.055595) (xy 170.804708 80.946684)
					(xy 170.98582 80.871665) (xy 171.178088 80.83342) (xy 171.374122 80.83342)
				)
			)
		)
	)
	(footprint "Vault:CAPC2013X140N"
		(layer "B.Cu")
		(at 144.976105 117.953605)
		(property "Reference" "C8"
			(at -2.69615 -0.12655 0)
			(unlocked yes)
			(layer "B.SilkS")
			(effects
				(font
					(face "Arial")
					(size 0.63 0.63)
					(thickness 0.254)
				)
				(justify mirror)
			)
		)
		(property "Value" "Murata_GRM21BR61A226ME51L"
			(at -6.86959 -8.07786 0)
			(unlocked yes)
			(layer "B.SilkS")
			(hide yes)
			(effects
				(font
					(face "Arial")
					(size 0.63 0.63)
					(thickness 0.254)
				)
				(justify mirror)
			)
		)
		(sheetname "SCH_SA45_DaughterCard")
		(sheetfile "SCH_SA45_DaughterCard.kicad_sch")
		(duplicate_pad_numbers_are_jumpers no)
		(fp_line
			(start -1.8 -1.1)
			(end 1.8 -1.1)
			(stroke
				(width 0.1)
				(type solid)
			)
			(layer "B.CrtYd")
		)
		(fp_line
			(start -1.8 1.1)
			(end -1.8 -1.1)
			(stroke
				(width 0.1)
				(type solid)
			)
			(layer "B.CrtYd")
		)
		(fp_line
			(start -1.8 1.1)
			(end 1.8 1.1)
			(stroke
				(width 0.1)
				(type solid)
			)
			(layer "B.CrtYd")
		)
		(fp_line
			(start 1.8 1.1)
			(end 1.8 -1.1)
			(stroke
				(width 0.1)
				(type solid)
			)
			(layer "B.CrtYd")
		)
		(fp_line
			(start -1 -0.65)
			(end 1 -0.65)
			(stroke
				(width 0.05)
				(type solid)
			)
			(layer "B.Fab")
		)
		(fp_line
			(start -1 0.65)
			(end -1 -0.65)
			(stroke
				(width 0.05)
				(type solid)
			)
			(layer "B.Fab")
		)
		(fp_line
			(start -1 0.65)
			(end 1 0.65)
			(stroke
				(width 0.05)
				(type solid)
			)
			(layer "B.Fab")
		)
		(fp_line
			(start 1 0.65)
			(end 1 -0.65)
			(stroke
				(width 0.05)
				(type solid)
			)
			(layer "B.Fab")
		)
		(fp_text_box "${REFERENCE}"
			(start 1.09003 0.20729)
			(end -1.09005 -0.20729)
			(margins 0 0 0 0)
			(angle 180)
			(layer "B.Fab")
			(effects
				(font
					(face "Arial")
					(size 0.315 0.315)
					(thickness 0.254)
				)
				(justify top mirror)
			)
			(border no)
			(stroke
				(width 0.1)
				(type default)
			)
			(knockout no)
		)
		(pad "1" smd rect
			(at -0.9 0)
			(size 1.3 1.65)
			(layers "B.Cu" "B.Mask" "B.Paste")
			(net "+5V")
			(solder_mask_margin 0.05)
			(solder_paste_margin 0)
		)
		(pad "2" smd rect
			(at 0.9 0)
			(size 1.3 1.65)
			(layers "B.Cu" "B.Mask" "B.Paste")
			(net "GND")
			(solder_mask_margin 0.05)
			(solder_paste_margin 0)
		)
	)
	(footprint "Vault:RESC1608X55X30ML15T15"
		(layer "B.Cu")
		(at 167.951105 110.103605 90)
		(property "Reference" "R1"
			(at 0.85017 1.62893 0)
			(unlocked yes)
			(layer "B.SilkS")
			(effects
				(font
					(face "Arial")
					(size 0.63 0.63)
					(thickness 0.254)
				)
				(justify mirror)
			)
		)
		(property "Value" "100k"
			(at -1.74803 -0.353675 0)
			(unlocked yes)
			(layer "B.SilkS")
			(hide yes)
			(effects
				(font
					(face "Arial")
					(size 0.63 0.63)
					(thickness 0.254)
				)
				(justify mirror)
			)
		)
		(sheetname "SCH_SA45_DaughterCard")
		(sheetfile "SCH_SA45_DaughterCard.kicad_sch")
		(duplicate_pad_numbers_are_jumpers no)
		(fp_line
			(start 1.7 -1.05)
			(end 1.7 1.05)
			(stroke
				(width 0.05)
				(type solid)
			)
			(layer "B.CrtYd")
		)
		(fp_line
			(start -1.7 -1.05)
			(end 1.7 -1.05)
			(stroke
				(width 0.05)
				(type solid)
			)
			(layer "B.CrtYd")
		)
		(fp_line
			(start -1.7 -1.05)
			(end -1.7 1.05)
			(stroke
				(width 0.05)
				(type solid)
			)
			(layer "B.CrtYd")
		)
		(fp_line
			(start 0 -0.475)
			(end 0 0.475)
			(stroke
				(width 0.1)
				(type solid)
			)
			(layer "B.CrtYd")
		)
		(fp_line
			(start -0.475 0)
			(end 0.475 0)
			(stroke
				(width 0.1)
				(type solid)
			)
			(layer "B.CrtYd")
		)
		(fp_line
			(start -1.7 1.05)
			(end 1.7 1.05)
			(stroke
				(width 0.05)
				(type solid)
			)
			(layer "B.CrtYd")
		)
		(pad "1" smd rect
			(at -0.725 0)
			(size 1.05 0.9)
			(layers "B.Cu" "B.Mask" "B.Paste")
			(net "GND")
		)
		(pad "2" smd rect
			(at 0.725 0)
			(size 1.05 0.9)
			(layers "B.Cu" "B.Mask" "B.Paste")
			(net "1PPS_IN")
		)
	)
	(footprint "Vault:RESC1005X040N"
		(layer "B.Cu")
		(at 145.116105 104.648605 90)
		(property "Reference" "R5"
			(at 3.27165 -0.000005 0)
			(unlocked yes)
			(layer "B.SilkS")
			(effects
				(font
					(face "Arial")
					(size 0.63 0.63)
					(thickness 0.254)
				)
				(justify mirror)
			)
		)
		(property "Value" "Panasonic_ERJ-2RKF2702X"
			(at -11.07338 -15.610155 0)
			(unlocked yes)
			(layer "B.SilkS")
			(hide yes)
			(effects
				(font
					(face "Arial")
					(size 0.63 0.63)
					(thickness 0.254)
				)
				(justify mirror)
			)
		)
		(sheetname "SCH_SA45_DaughterCard")
		(sheetfile "SCH_SA45_DaughterCard.kicad_sch")
		(duplicate_pad_numbers_are_jumpers no)
		(fp_line
			(start 0.95 -0.5)
			(end 0.95 0.5)
			(stroke
				(width 0.1)
				(type solid)
			)
			(layer "B.CrtYd")
		)
		(fp_line
			(start -0.95 -0.5)
			(end 0.95 -0.5)
			(stroke
				(width 0.1)
				(type solid)
			)
			(layer "B.CrtYd")
		)
		(fp_line
			(start -0.95 -0.5)
			(end -0.95 0.5)
			(stroke
				(width 0.1)
				(type solid)
			)
			(layer "B.CrtYd")
		)
		(fp_line
			(start -0.95 0.5)
			(end 0.95 0.5)
			(stroke
				(width 0.1)
				(type solid)
			)
			(layer "B.CrtYd")
		)
		(fp_line
			(start 0.5 -0.25)
			(end 0.5 0.25)
			(stroke
				(width 0.05)
				(type solid)
			)
			(layer "B.Fab")
		)
		(fp_line
			(start -0.5 -0.25)
			(end 0.5 -0.25)
			(stroke
				(width 0.05)
				(type solid)
			)
			(layer "B.Fab")
		)
		(fp_line
			(start -0.5 -0.25)
			(end -0.5 0.25)
			(stroke
				(width 0.05)
				(type solid)
			)
			(layer "B.Fab")
		)
		(fp_line
			(start -0.5 0.25)
			(end 0.5 0.25)
			(stroke
				(width 0.05)
				(type solid)
			)
			(layer "B.Fab")
		)
		(fp_text_box "${REFERENCE}"
			(start 0.20727 -1.09004)
			(end -0.20726 1.09004)
			(margins 0 0 0 0)
			(angle -90)
			(layer "B.Fab")
			(effects
				(font
					(face "Arial")
					(size 0.315 0.315)
					(thickness 0.254)
				)
				(justify top mirror)
			)
			(border no)
			(stroke
				(width 0.1)
				(type default)
			)
			(knockout no)
		)
		(pad "1" smd rect
			(at -0.48 0 90)
			(size 0.57 0.62)
			(layers "B.Cu" "B.Mask" "B.Paste")
			(net "NetR5_1")
			(solder_mask_margin 0.05)
			(solder_paste_margin 0)
		)
		(pad "2" smd rect
			(at 0.48 0 90)
			(size 0.57 0.62)
			(layers "B.Cu" "B.Mask" "B.Paste")
			(net "NetC9_1")
			(solder_mask_margin 0.05)
			(solder_paste_margin 0)
		)
	)
	(footprint "Vault:CAPC1005X055N"
		(layer "B.Cu")
		(at 145.276105 110.553605)
		(property "Reference" "C6"
			(at -2.1 -0.12655 0)
			(unlocked yes)
			(layer "B.SilkS")
			(effects
				(font
					(face "Arial")
					(size 0.63 0.63)
					(thickness 0.254)
				)
				(justify mirror)
			)
		)
		(property "Value" "Murata_GRM155R61H104KE14D"
			(at -28.015845 -0.3605 0)
			(unlocked yes)
			(layer "B.SilkS")
			(hide yes)
			(effects
				(font
					(face "Arial")
					(size 0.63 0.63)
					(thickness 0.254)
				)
				(justify mirror)
			)
		)
		(sheetname "SCH_SA45_DaughterCard")
		(sheetfile "SCH_SA45_DaughterCard.kicad_sch")
		(duplicate_pad_numbers_are_jumpers no)
		(fp_line
			(start -0.95 -0.5)
			(end 0.95 -0.5)
			(stroke
				(width 0.1)
				(type solid)
			)
			(layer "B.CrtYd")
		)
		(fp_line
			(start -0.95 0.5)
			(end -0.95 -0.5)
			(stroke
				(width 0.1)
				(type solid)
			)
			(layer "B.CrtYd")
		)
		(fp_line
			(start -0.95 0.5)
			(end 0.95 0.5)
			(stroke
				(width 0.1)
				(type solid)
			)
			(layer "B.CrtYd")
		)
		(fp_line
			(start 0.95 0.5)
			(end 0.95 -0.5)
			(stroke
				(width 0.1)
				(type solid)
			)
			(layer "B.CrtYd")
		)
		(fp_line
			(start -0.5 -0.25)
			(end 0.5 -0.25)
			(stroke
				(width 0.05)
				(type solid)
			)
			(layer "B.Fab")
		)
		(fp_line
			(start -0.5 0.25)
			(end -0.5 -0.25)
			(stroke
				(width 0.05)
				(type solid)
			)
			(layer "B.Fab")
		)
		(fp_line
			(start -0.5 0.25)
			(end 0.5 0.25)
			(stroke
				(width 0.05)
				(type solid)
			)
			(layer "B.Fab")
		)
		(fp_line
			(start 0.5 0.25)
			(end 0.5 -0.25)
			(stroke
				(width 0.05)
				(type solid)
			)
			(layer "B.Fab")
		)
		(fp_text_box "${REFERENCE}"
			(start 1.09006 0.20729)
			(end -1.09002 -0.20729)
			(margins 0 0 0 0)
			(angle 180)
			(layer "B.Fab")
			(effects
				(font
					(face "Arial")
					(size 0.315 0.315)
					(thickness 0.254)
				)
				(justify top mirror)
			)
			(border no)
			(stroke
				(width 0.1)
				(type default)
			)
			(knockout no)
		)
		(pad "1" smd rect
			(at -0.46 0)
			(size 0.6 0.62)
			(layers "B.Cu" "B.Mask" "B.Paste")
			(net "+5V")
			(solder_mask_margin 0.05)
			(solder_paste_margin 0)
		)
		(pad "2" smd rect
			(at 0.46 0)
			(size 0.6 0.62)
			(layers "B.Cu" "B.Mask" "B.Paste")
			(net "GND")
			(solder_mask_margin 0.05)
			(solder_paste_margin 0)
		)
	)
	(footprint "FAB_SA45_DaughterCard:Keystone_4871"
		(locked yes)
		(layer "B.Cu")
		(at 132.561105 86.743605 180)
		(property "Reference" "J6"
			(at 0.106965 -3.74429 0)
			(unlocked yes)
			(layer "B.SilkS")
			(effects
				(font
					(face "Arial")
					(size 0.63 0.63)
					(thickness 0.254)
				)
				(justify mirror)
			)
		)
		(property "Value" "Keystone_4871"
			(at 6.3343 -5.019802 0)
			(unlocked yes)
			(layer "B.SilkS")
			(hide yes)
			(effects
				(font
					(size 1.524 1.524)
					(thickness 0.254)
				)
				(justify mirror)
			)
		)
		(sheetname "SCH_SA45_DaughterCard")
		(sheetfile "SCH_SA45_DaughterCard.kicad_sch")
		(duplicate_pad_numbers_are_jumpers no)
		(fp_line
			(start 3.4 3.4)
			(end -3.4 3.4)
			(stroke
				(width 0.1)
				(type solid)
			)
			(layer "B.CrtYd")
		)
		(fp_line
			(start 3.4 -3.4)
			(end 3.4 3.4)
			(stroke
				(width 0.1)
				(type solid)
			)
			(layer "B.CrtYd")
		)
		(fp_line
			(start 3.4 -3.4)
			(end -3.4 -3.4)
			(stroke
				(width 0.1)
				(type solid)
			)
			(layer "B.CrtYd")
		)
		(fp_line
			(start -3.4 -0.8)
			(end -3.4 3.4)
			(stroke
				(width 0.1)
				(type solid)
			)
			(layer "B.CrtYd")
		)
		(fp_line
			(start -3.4 -3.4)
			(end -3.4 -0.8)
			(stroke
				(width 0.1)
				(type solid)
			)
			(layer "B.CrtYd")
		)
		(fp_text user ""
			(at 0.367795 0.63446 360)
			(unlocked yes)
			(layer "B.Fab")
			(effects
				(font
					(face "Arial")
					(size 0.63 0.63)
					(thickness 0.254)
				)
				(justify mirror)
			)
		)
		(fp_text user "${REFERENCE}"
			(at -0.001845 0.19946 360)
			(unlocked yes)
			(layer "B.Fab")
			(effects
				(font
					(face "Arial")
					(size 0.63 0.63)
					(thickness 0.254)
				)
				(justify mirror)
			)
		)
		(pad "Hole" thru_hole circle
			(at 0 0 180)
			(size 0 0)
			(drill 3.7)
			(layers "*.Cu" "*.Mask")
			(remove_unused_layers no)
			(thermal_bridge_angle 90)
		)
		(pad "MT" smd circle
			(at 0 0 180)
			(size 6.2 6.2)
			(layers "B.Cu" "B.Mask" "B.Paste")
			(solder_mask_margin 0.05)
			(thermal_bridge_angle 90)
		)
	)
	(footprint "Vault:CAPC0603X033N"
		(layer "B.Cu")
		(at 144.786105 103.053605 180)
		(property "Reference" "C9"
			(at -0.33 2.60155 0)
			(unlocked yes)
			(layer "B.SilkS")
			(effects
				(font
					(face "Arial")
					(size 0.63 0.63)
					(thickness 0.254)
				)
				(justify mirror)
			)
		)
		(property "Value" "Murata_GRM033R61A332KA01D"
			(at 18.677945 -13.23094 0)
			(unlocked yes)
			(layer "B.SilkS")
			(hide yes)
			(effects
				(font
					(face "Arial")
					(size 0.63 0.63)
					(thickness 0.254)
				)
				(justify mirror)
			)
		)
		(sheetname "SCH_SA45_DaughterCard")
		(sheetfile "SCH_SA45_DaughterCard.kicad_sch")
		(duplicate_pad_numbers_are_jumpers no)
		(fp_line
			(start 0.75 0.4)
			(end -0.75 0.4)
			(stroke
				(width 0.1)
				(type solid)
			)
			(layer "B.CrtYd")
		)
		(fp_line
			(start 0.75 -0.4)
			(end 0.75 0.4)
			(stroke
				(width 0.1)
				(type solid)
			)
			(layer "B.CrtYd")
		)
		(fp_line
			(start 0.75 -0.4)
			(end -0.75 -0.4)
			(stroke
				(width 0.1)
				(type solid)
			)
			(layer "B.CrtYd")
		)
		(fp_line
			(start -0.75 -0.4)
			(end -0.75 0.4)
			(stroke
				(width 0.1)
				(type solid)
			)
			(layer "B.CrtYd")
		)
		(fp_line
			(start 0.3 0.15)
			(end -0.3 0.15)
			(stroke
				(width 0.05)
				(type solid)
			)
			(layer "B.Fab")
		)
		(fp_line
			(start 0.3 -0.15)
			(end 0.3 0.15)
			(stroke
				(width 0.05)
				(type solid)
			)
			(layer "B.Fab")
		)
		(fp_line
			(start 0.3 -0.15)
			(end -0.3 -0.15)
			(stroke
				(width 0.05)
				(type solid)
			)
			(layer "B.Fab")
		)
		(fp_line
			(start -0.3 -0.15)
			(end -0.3 0.15)
			(stroke
				(width 0.05)
				(type solid)
			)
			(layer "B.Fab")
		)
		(fp_text_box "${REFERENCE}"
			(start 1.09004 0.20727)
			(end -1.09004 -0.20726)
			(margins 0 0 0 0)
			(angle -180)
			(layer "B.Fab")
			(effects
				(font
					(face "Arial")
					(size 0.315 0.315)
					(thickness 0.254)
				)
				(justify top mirror)
			)
			(border no)
			(stroke
				(width 0.1)
				(type default)
			)
			(knockout no)
		)
		(pad "1" smd rect
			(at -0.33 0 180)
			(size 0.46 0.42)
			(layers "B.Cu" "B.Mask" "B.Paste")
			(net "NetC9_1")
			(solder_mask_margin 0.05)
			(solder_paste_margin 0)
		)
		(pad "2" smd rect
			(at 0.33 0 180)
			(size 0.46 0.42)
			(layers "B.Cu" "B.Mask" "B.Paste")
			(net "GND")
			(solder_mask_margin 0.05)
			(solder_paste_margin 0)
		)
	)
	(footprint "Vault:CAPC1005X061N"
		(layer "B.Cu")
		(at 166.471105 115.403605)
		(property "Reference" "C1"
			(at 1.779995 -0.12655 0)
			(unlocked yes)
			(layer "B.SilkS")
			(effects
				(font
					(face "Arial")
					(size 0.63 0.63)
					(thickness 0.254)
				)
				(justify mirror)
			)
		)
		(property "Value" "Murata_GRM155R6YA105KE11D"
			(at -9.64079 5.13679 0)
			(unlocked yes)
			(layer "B.SilkS")
			(hide yes)
			(effects
				(font
					(face "Arial")
					(size 0.63 0.63)
					(thickness 0.254)
				)
				(justify mirror)
			)
		)
		(sheetname "SCH_SA45_DaughterCard")
		(sheetfile "SCH_SA45_DaughterCard.kicad_sch")
		(duplicate_pad_numbers_are_jumpers no)
		(fp_line
			(start -0.95 -0.5)
			(end 0.95 -0.5)
			(stroke
				(width 0.1)
				(type solid)
			)
			(layer "B.CrtYd")
		)
		(fp_line
			(start -0.95 0.5)
			(end -0.95 -0.5)
			(stroke
				(width 0.1)
				(type solid)
			)
			(layer "B.CrtYd")
		)
		(fp_line
			(start -0.95 0.5)
			(end 0.95 0.5)
			(stroke
				(width 0.1)
				(type solid)
			)
			(layer "B.CrtYd")
		)
		(fp_line
			(start 0.95 0.5)
			(end 0.95 -0.5)
			(stroke
				(width 0.1)
				(type solid)
			)
			(layer "B.CrtYd")
		)
		(fp_line
			(start -0.5 -0.25)
			(end 0.5 -0.25)
			(stroke
				(width 0.05)
				(type solid)
			)
			(layer "B.Fab")
		)
		(fp_line
			(start -0.5 0.25)
			(end -0.5 -0.25)
			(stroke
				(width 0.05)
				(type solid)
			)
			(layer "B.Fab")
		)
		(fp_line
			(start -0.5 0.25)
			(end 0.5 0.25)
			(stroke
				(width 0.05)
				(type solid)
			)
			(layer "B.Fab")
		)
		(fp_line
			(start 0.5 0.25)
			(end 0.5 -0.25)
			(stroke
				(width 0.05)
				(type solid)
			)
			(layer "B.Fab")
		)
		(fp_text_box "${REFERENCE}"
			(start 1.14717 0.20756)
			(end -1.14713 -0.20757)
			(margins 0 0 0 0)
			(angle 180)
			(layer "B.Fab")
			(effects
				(font
					(face "Arial")
					(size 0.315 0.315)
					(thickness 0.254)
				)
				(justify top mirror)
			)
			(border no)
			(stroke
				(width 0.1)
				(type default)
			)
			(knockout no)
		)
		(pad "1" smd rect
			(at -0.46 0)
			(size 0.6 0.62)
			(layers "B.Cu" "B.Mask" "B.Paste")
			(net "+3.3V_OSC")
			(solder_mask_margin 0.05)
			(solder_paste_margin 0)
		)
		(pad "2" smd rect
			(at 0.46 0)
			(size 0.6 0.62)
			(layers "B.Cu" "B.Mask" "B.Paste")
			(net "GND")
			(solder_mask_margin 0.05)
			(solder_paste_margin 0)
		)
	)
	(footprint "Vault:FID_1p0mm"
		(layer "B.Cu")
		(at 125.776105 81.828605 180)
		(property "Reference" "Designator5"
			(at 7.084135 3.019298 0)
			(unlocked yes)
			(layer "B.SilkS")
			(hide yes)
			(effects
				(font
					(size 1.524 1.524)
					(thickness 0.254)
				)
				(justify mirror)
			)
		)
		(property "Value" "Comment"
			(at 5.07844 0.707898 0)
			(unlocked yes)
			(layer "B.SilkS")
			(hide yes)
			(effects
				(font
					(size 1.524 1.524)
					(thickness 0.254)
				)
				(justify mirror)
			)
		)
		(sheetfile ".kicad_sch")
		(duplicate_pad_numbers_are_jumpers no)
		(fp_circle
			(center 0 0)
			(end 0 1)
			(stroke
				(width 0.1)
				(type solid)
			)
			(fill no)
			(layer "B.CrtYd")
		)
		(pad "1" smd circle
			(at 0 0 90)
			(size 1 1)
			(layers "B.Cu" "B.Mask" "B.Paste")
			(solder_mask_margin 0.5)
			(solder_paste_margin -6)
			(thermal_bridge_angle 90)
		)
		(zone
			(layer "B.Cu")
			(hatch edge 0.5)
			(connect_pads
				(clearance 0)
			)
			(min_thickness 0.25)
			(keepout
				(tracks not_allowed)
				(vias not_allowed)
				(pads allowed)
				(copperpour not_allowed)
				(footprints allowed)
			)
			(placement
				(enabled no)
				(sheetname "")
			)
			(fill
				(thermal_gap 0.5)
				(thermal_bridge_width 0.5)
				(island_removal_mode 0)
			)
			(polygon
				(pts
					(xy 126.06639 80.871665) (xy 126.247502 80.946684) (xy 126.410498 81.055595) (xy 126.549115 81.194212)
					(xy 126.658026 81.357208) (xy 126.733045 81.53832) (xy 126.77129 81.730588) (xy 126.77129 81.926622)
					(xy 126.733045 82.11889) (xy 126.658026 82.300002) (xy 126.549115 82.462998) (xy 126.410498 82.601615)
					(xy 126.247502 82.710526) (xy 126.06639 82.785545) (xy 125.874122 82.82379) (xy 125.678088 82.82379)
					(xy 125.48582 82.785545) (xy 125.304708 82.710526) (xy 125.141712 82.601615) (xy 125.003095 82.462998)
					(xy 124.894184 82.300002) (xy 124.819165 82.11889) (xy 124.78092 81.926622) (xy 124.78092 81.762779)
					(xy 125.276105 81.762779) (xy 125.276105 81.894431) (xy 125.31018 82.021598) (xy 125.376006 82.135612)
					(xy 125.469098 82.228704) (xy 125.583112 82.29453) (xy 125.710279 82.328605) (xy 125.841931 82.328605)
					(xy 125.969098 82.29453) (xy 126.083112 82.228704) (xy 126.176204 82.135612) (xy 126.24203 82.021598)
					(xy 126.276105 81.894431) (xy 126.276105 81.762779) (xy 126.24203 81.635612) (xy 126.176204 81.521598)
					(xy 126.083112 81.428506) (xy 125.969098 81.36268) (xy 125.841931 81.328605) (xy 125.710279 81.328605)
					(xy 125.583112 81.36268) (xy 125.469098 81.428506) (xy 125.376006 81.521598) (xy 125.31018 81.635612)
					(xy 125.276105 81.762779) (xy 124.78092 81.762779) (xy 124.78092 81.730588) (xy 124.819165 81.53832)
					(xy 124.894184 81.357208) (xy 125.003095 81.194212) (xy 125.141712 81.055595) (xy 125.304708 80.946684)
					(xy 125.48582 80.871665) (xy 125.678088 80.83342) (xy 125.874122 80.83342)
				)
			)
		)
	)
	(footprint "Vault:TH000V_300DIAx400_001mt_9774040243R"
		(locked yes)
		(layer "B.Cu")
		(at 148.401105 83.203605 180)
		(property "Reference" "J2"
			(at -0.00185 -3.59429 0)
			(unlocked yes)
			(layer "B.SilkS")
			(effects
				(font
					(face "Arial")
					(size 0.63 0.63)
					(thickness 0.254)
				)
				(justify mirror)
			)
		)
		(property "Value" "Wurth_9774040243R"
			(at 9.66063 -4.57418 0)
			(unlocked yes)
			(layer "B.SilkS")
			(hide yes)
			(effects
				(font
					(face "Arial")
					(size 0.63 0.63)
					(thickness 0.254)
				)
				(justify mirror)
			)
		)
		(sheetname "SCH_SA45_DaughterCard")
		(sheetfile "SCH_SA45_DaughterCard.kicad_sch")
		(duplicate_pad_numbers_are_jumpers no)
		(fp_line
			(start 3.1 3.1)
			(end -3.1 3.1)
			(stroke
				(width 0.1)
				(type solid)
			)
			(layer "B.CrtYd")
		)
		(fp_line
			(start 3.1 -3.1)
			(end 3.1 3.1)
			(stroke
				(width 0.1)
				(type solid)
			)
			(layer "B.CrtYd")
		)
		(fp_line
			(start 3.1 -3.1)
			(end -3.1 -3.1)
			(stroke
				(width 0.1)
				(type solid)
			)
			(layer "B.CrtYd")
		)
		(fp_line
			(start -3.1 -3.1)
			(end -3.1 3.1)
			(stroke
				(width 0.1)
				(type solid)
			)
			(layer "B.CrtYd")
		)
		(fp_circle
			(center 0 0)
			(end 0 1.5)
			(stroke
				(width 0.1)
				(type solid)
			)
			(fill no)
			(layer "B.Fab")
		)
		(fp_text user "${REFERENCE}"
			(at -0.002345 0.166251 360)
			(unlocked yes)
			(layer "B.Fab")
			(effects
				(font
					(face "Arial")
					(size 0.8001 0.8001)
					(thickness 0.254)
				)
				(justify mirror)
			)
		)
		(pad "" np_thru_hole circle
			(at 0 0 180)
			(size 5.3 5.3)
			(drill 3)
			(layers "*.Cu" "*.Mask")
			(solder_mask_margin 0.2)
			(solder_paste_margin -2147.48364)
			(thermal_bridge_angle 90)
		)
	)
	(gr_poly
		(pts
			(xy 152.875855 83.099365) (xy 152.864455 83.100625) (xy 152.847975 83.108235) (xy 152.837825 83.110775)
			(xy 152.820085 83.112035) (xy 152.813745 83.114575) (xy 152.805505 83.117745) (xy 152.798535 83.119645)
			(xy 152.793465 83.120915) (xy 152.784585 83.122175) (xy 152.779515 83.123445) (xy 152.763035 83.122175)
			(xy 152.759235 83.120915) (xy 152.750995 83.119005) (xy 152.744655 83.116475) (xy 152.730085 83.112035)
			(xy 152.717405 83.110775) (xy 152.707265 83.109505) (xy 152.685715 83.099365) (xy 152.677475 83.096195)
			(xy 152.675575 83.094295) (xy 152.673035 83.093025) (xy 152.665435 83.087955) (xy 152.658455 83.086055)
			(xy 152.654025 83.084155) (xy 152.647055 83.078445) (xy 152.643885 83.075275) (xy 152.641345 83.074005)
			(xy 152.635645 83.068305) (xy 152.634375 83.065765) (xy 152.631205 83.062605) (xy 152.628675 83.061335)
			(xy 152.624235 83.056895) (xy 152.622965 83.054355) (xy 152.619795 83.051195) (xy 152.617265 83.049925)
			(xy 152.611555 83.044215) (xy 152.610285 83.041685) (xy 152.607115 83.038515) (xy 152.604585 83.037245)
			(xy 152.600145 83.032815) (xy 152.598875 83.030275) (xy 152.591275 83.022675) (xy 152.590005 83.020135)
			(xy 152.587465 83.013795) (xy 152.586205 83.008725) (xy 152.577325 82.996045) (xy 152.575425 82.989075)
			(xy 152.572895 82.982735) (xy 152.567185 82.971965) (xy 152.564655 82.963095) (xy 152.560215 82.935835)
			(xy 152.558315 82.931395) (xy 152.555785 82.925065) (xy 152.554515 82.919985) (xy 152.553245 82.911115)
			(xy 152.551975 82.898445) (xy 152.553245 82.869285) (xy 152.554515 82.865475) (xy 152.555785 82.856615)
			(xy 152.562115 82.842665) (xy 152.563385 82.826185) (xy 152.566555 82.812875) (xy 152.573525 82.799565)
			(xy 152.576695 82.791325) (xy 152.579225 82.784985) (xy 152.582395 82.781815) (xy 152.583665 82.779285)
			(xy 152.587465 82.770405) (xy 152.590635 82.762165) (xy 152.598875 82.753925) (xy 152.600145 82.751395)
			(xy 152.618525 82.733015) (xy 152.621065 82.731745) (xy 152.622965 82.729845) (xy 152.624235 82.727305)
			(xy 152.643885 82.707655) (xy 152.646415 82.706395) (xy 152.652755 82.700055) (xy 152.659095 82.697515)
			(xy 152.667335 82.694345) (xy 152.680645 82.687375) (xy 152.690785 82.684845) (xy 152.700295 82.682945)
			(xy 152.711065 82.678505) (xy 152.716135 82.677235) (xy 152.728815 82.675975) (xy 152.745295 82.674705)
			(xy 152.773185 82.673435) (xy 152.828955 82.674705) (xy 152.832755 82.675975) (xy 152.850505 82.677235)
			(xy 152.864455 82.683575) (xy 152.870785 82.686115) (xy 152.882195 82.692445) (xy 152.893605 82.697515)
			(xy 152.905015 82.703855) (xy 152.916425 82.708925) (xy 152.927835 82.715265) (xy 152.930365 82.719065)
			(xy 152.932905 82.720335) (xy 152.939875 82.726045) (xy 152.945575 82.734285) (xy 152.948115 82.735545)
			(xy 152.950015 82.737455) (xy 152.952555 82.743785) (xy 152.954455 82.750755) (xy 152.957625 82.755195)
			(xy 152.963965 82.761535) (xy 152.965225 82.764075) (xy 152.970935 82.771045) (xy 152.974105 82.774215)
			(xy 152.975375 82.776745) (xy 152.977905 82.783085) (xy 152.981075 82.791325) (xy 152.986785 82.800835)
			(xy 152.989315 82.810975) (xy 152.991215 82.821745) (xy 152.996915 82.836325) (xy 152.999455 82.854075)
			(xy 153.001355 82.890205) (xy 153.001985 82.903515) (xy 153.000725 82.907315) (xy 152.999455 82.942805)
			(xy 152.998185 82.946605) (xy 152.996915 82.960555) (xy 152.990575 82.974495) (xy 152.987415 82.982735)
			(xy 152.982975 82.989715) (xy 152.976635 83.003655) (xy 152.970305 83.015065) (xy 152.965225 83.026475)
			(xy 152.960155 83.035345) (xy 152.955085 83.040415) (xy 152.953825 83.042955) (xy 152.948115 83.049925)
			(xy 152.945575 83.051195) (xy 152.941145 83.055625) (xy 152.939875 83.058165) (xy 152.935435 83.062605)
			(xy 152.929105 83.066405) (xy 152.922765 83.072745) (xy 152.917695 83.074005) (xy 152.909455 83.077175)
			(xy 152.901215 83.085415) (xy 152.892335 83.090495) (xy 152.887265 83.095565) (xy 152.880935 83.098095)
			(xy 152.876495 83.098735)
		)
		(stroke
			(width 0)
			(type default)
		)
		(fill yes)
		(layer "F.Cu")
	)
	(gr_poly
		(pts
			(xy 152.698385 83.421345) (xy 152.709795 83.416275) (xy 152.722475 83.415005) (xy 152.733885 83.413735)
			(xy 152.742755 83.409935) (xy 152.749095 83.407395) (xy 152.754165 83.406135) (xy 152.768745 83.404235)
			(xy 152.795995 83.403595) (xy 152.799805 83.404865) (xy 152.813115 83.406765) (xy 152.818185 83.408035)
			(xy 152.825155 83.411205) (xy 152.834025 83.413735) (xy 152.848605 83.415635) (xy 152.856215 83.416905)
			(xy 152.861285 83.418175) (xy 152.874595 83.425145) (xy 152.886635 83.429585) (xy 152.893605 83.434025)
			(xy 152.896145 83.436555) (xy 152.911985 83.442265) (xy 152.920225 83.450505) (xy 152.922765 83.451775)
			(xy 152.925935 83.453675) (xy 152.927205 83.456205) (xy 152.953825 83.482825) (xy 152.955085 83.485365)
			(xy 152.962695 83.492965) (xy 152.967135 83.505005) (xy 152.973475 83.515155) (xy 152.976635 83.522125)
			(xy 152.979805 83.530365) (xy 152.986145 83.540505) (xy 152.990575 83.551275) (xy 152.993745 83.559515)
			(xy 152.996915 83.566495) (xy 152.998185 83.575365) (xy 153.000725 83.609595) (xy 153.001985 83.636215)
			(xy 153.000725 83.640015) (xy 152.998815 83.677405) (xy 152.996285 83.692625) (xy 152.991845 83.703395)
			(xy 152.989315 83.713535) (xy 152.988045 83.722405) (xy 152.982975 83.731285) (xy 152.977905 83.742695)
			(xy 152.974735 83.750935) (xy 152.966495 83.759175) (xy 152.965225 83.761705) (xy 152.959525 83.768675)
			(xy 152.956355 83.771845) (xy 152.952555 83.780725) (xy 152.951285 83.785795) (xy 152.945575 83.792765)
			(xy 152.943045 83.794035) (xy 152.939875 83.797205) (xy 152.938605 83.799735) (xy 152.936705 83.801635)
			(xy 152.930365 83.804175) (xy 152.922125 83.807345) (xy 152.917695 83.810515) (xy 152.911355 83.816855)
			(xy 152.908815 83.818115) (xy 152.901845 83.823825) (xy 152.898675 83.826995) (xy 152.882835 83.832695)
			(xy 152.880935 83.834595) (xy 152.869525 83.839665) (xy 152.864455 83.840935) (xy 152.853675 83.842835)
			(xy 152.847335 83.845375) (xy 152.839095 83.848545) (xy 152.826425 83.849805) (xy 152.821345 83.851075)
			(xy 152.786495 83.852975) (xy 152.768105 83.853615) (xy 152.764305 83.852345) (xy 152.730085 83.851075)
			(xy 152.726275 83.849805) (xy 152.713605 83.848545) (xy 152.699655 83.842205) (xy 152.691415 83.839035)
			(xy 152.684445 83.834595) (xy 152.670505 83.828255) (xy 152.659095 83.821915) (xy 152.647685 83.816855)
			(xy 152.638815 83.811775) (xy 152.633735 83.806705) (xy 152.631205 83.805445) (xy 152.624235 83.799735)
			(xy 152.622965 83.797205) (xy 152.617265 83.791495) (xy 152.614725 83.790235) (xy 152.612825 83.788325)
			(xy 152.611555 83.785795) (xy 152.605855 83.780085) (xy 152.603315 83.778825) (xy 152.600145 83.775655)
			(xy 152.598875 83.773115) (xy 152.593175 83.766145) (xy 152.590005 83.762975) (xy 152.587465 83.756635)
			(xy 152.586205 83.751565) (xy 152.581135 83.742695) (xy 152.576055 83.731285) (xy 152.573525 83.716075)
			(xy 152.564655 83.697055) (xy 152.563385 83.688185) (xy 152.560855 83.678045) (xy 152.555785 83.666635)
			(xy 152.554515 83.661565) (xy 152.553245 83.652685) (xy 152.550715 83.624805) (xy 152.551975 83.621005)
			(xy 152.553875 83.597545) (xy 152.555145 83.591205) (xy 152.559585 83.580435) (xy 152.562115 83.574095)
			(xy 152.563385 83.565225) (xy 152.565285 83.556985) (xy 152.574795 83.538605) (xy 152.577965 83.530365)
			(xy 152.582395 83.523385) (xy 152.587465 83.511985) (xy 152.592545 83.503105) (xy 152.596345 83.499305)
			(xy 152.597615 83.496765) (xy 152.600145 83.494235) (xy 152.601415 83.491695) (xy 152.603315 83.489795)
			(xy 152.605855 83.488525) (xy 152.612825 83.481555) (xy 152.614095 83.479025) (xy 152.615995 83.477115)
			(xy 152.618525 83.475855) (xy 152.625505 83.468875) (xy 152.626765 83.466345) (xy 152.628675 83.464445)
			(xy 152.631205 83.463175) (xy 152.636905 83.457475) (xy 152.638175 83.454935) (xy 152.641345 83.451775)
			(xy 152.643885 83.450505) (xy 152.650855 83.444795) (xy 152.654025 83.441625) (xy 152.660355 83.439095)
			(xy 152.665435 83.437825) (xy 152.679375 83.428955) (xy 152.691415 83.424515) (xy 152.697125 83.421345)
		)
		(stroke
			(width 0)
			(type default)
		)
		(fill yes)
		(layer "F.Cu")
	)
	(gr_poly
		(pts
			(xy 152.664165 84.914635) (xy 152.676205 84.910195) (xy 152.682545 84.907665) (xy 152.690155 84.902585)
			(xy 152.697125 84.900685) (xy 152.705995 84.899415) (xy 152.718035 84.894985) (xy 152.728815 84.891815)
			(xy 152.733885 84.890545) (xy 152.761135 84.888645) (xy 152.776345 84.887375) (xy 152.787125 84.886745)
			(xy 152.790925 84.888015) (xy 152.820715 84.889915) (xy 152.833395 84.891185) (xy 152.839735 84.892445)
			(xy 152.846075 84.894985) (xy 152.854315 84.898155) (xy 152.863185 84.899415) (xy 152.868255 84.900685)
			(xy 152.876495 84.903855) (xy 152.884095 84.908925) (xy 152.898045 84.913995) (xy 152.902485 84.917165)
			(xy 152.908815 84.923505) (xy 152.911355 84.924775) (xy 152.929735 84.943155) (xy 152.931005 84.945685)
			(xy 152.935435 84.948855) (xy 152.942415 84.955835) (xy 152.943675 84.958365) (xy 152.948115 84.961535)
			(xy 152.966495 84.979915) (xy 152.967765 84.982455) (xy 152.974105 84.988795) (xy 152.975375 84.991325)
			(xy 152.977905 84.997665) (xy 152.981075 85.005905) (xy 152.986785 85.015415) (xy 152.989315 85.025545)
			(xy 152.991215 85.036325) (xy 152.993745 85.042665) (xy 152.996915 85.050905) (xy 152.998185 85.059775)
			(xy 152.999455 85.076255) (xy 153.000725 85.088935) (xy 153.001985 85.120625) (xy 153.000725 85.124425)
			(xy 152.999455 85.159925) (xy 152.998185 85.163725) (xy 152.996915 85.176405) (xy 152.991845 85.187805)
			(xy 152.989315 85.197955) (xy 152.988045 85.206825) (xy 152.982975 85.215695) (xy 152.977905 85.227105)
			(xy 152.974735 85.235345) (xy 152.966495 85.243585) (xy 152.965225 85.246125) (xy 152.960795 85.251825)
			(xy 152.958255 85.253095) (xy 152.939875 85.271475) (xy 152.938605 85.274005) (xy 152.936705 85.275905)
			(xy 152.934175 85.277175) (xy 152.928465 85.282885) (xy 152.927205 85.285415) (xy 152.924035 85.288585)
			(xy 152.921495 85.289855) (xy 152.914525 85.295555) (xy 152.911355 85.298725) (xy 152.905015 85.301265)
			(xy 152.896775 85.304435) (xy 152.892335 85.307605) (xy 152.875855 85.315205) (xy 152.854315 85.325345)
			(xy 152.842905 85.326615) (xy 152.839095 85.327885) (xy 152.830225 85.331685) (xy 152.821345 85.334225)
			(xy 152.812475 85.335495) (xy 152.787755 85.337395) (xy 152.766845 85.338025) (xy 152.763035 85.336755)
			(xy 152.734515 85.334855) (xy 152.728185 85.333585) (xy 152.718035 85.329785) (xy 152.707265 85.326615)
			(xy 152.702195 85.325345) (xy 152.692685 85.323445) (xy 152.676835 85.315205) (xy 152.668595 85.312045)
			(xy 152.664165 85.310135) (xy 152.660995 85.306965) (xy 152.660355 85.305065) (xy 152.657825 85.303805)
			(xy 152.655285 85.301265) (xy 152.652755 85.299995) (xy 152.647055 85.294295) (xy 152.645785 85.291755)
			(xy 152.643885 85.289855) (xy 152.641345 85.288585) (xy 152.635645 85.282885) (xy 152.634375 85.280345)
			(xy 152.631205 85.277175) (xy 152.628675 85.275905) (xy 152.624235 85.271475) (xy 152.622965 85.268935)
			(xy 152.619795 85.265765) (xy 152.617265 85.264505) (xy 152.611555 85.258795) (xy 152.610285 85.256265)
			(xy 152.607115 85.253095) (xy 152.604585 85.251825) (xy 152.600145 85.247395) (xy 152.598875 85.244855)
			(xy 152.591275 85.237245) (xy 152.590005 85.234715) (xy 152.587465 85.228375) (xy 152.584305 85.220135)
			(xy 152.582395 85.218235) (xy 152.581135 85.215695) (xy 152.578595 85.213165) (xy 152.574155 85.201115)
			(xy 152.571625 85.194785) (xy 152.565925 85.185275) (xy 152.563385 85.176405) (xy 152.561485 85.164355)
			(xy 152.554515 85.147245) (xy 152.550715 85.109215) (xy 152.551975 85.105415) (xy 152.553875 85.081955)
			(xy 152.555145 85.076895) (xy 152.558955 85.066755) (xy 152.562115 85.058515) (xy 152.564015 85.046465)
			(xy 152.565285 85.041395) (xy 152.574795 85.023015) (xy 152.577965 85.014775) (xy 152.582395 85.007805)
			(xy 152.588735 84.993865) (xy 152.595075 84.982455) (xy 152.600145 84.971045) (xy 152.605215 84.962165)
			(xy 152.610285 84.957095) (xy 152.611555 84.954565) (xy 152.614725 84.950125) (xy 152.617265 84.948855)
			(xy 152.619795 84.946325) (xy 152.622335 84.945055) (xy 152.627405 84.937445) (xy 152.629935 84.936185)
			(xy 152.636905 84.930475) (xy 152.641345 84.926035) (xy 152.657185 84.920335) (xy 152.660355 84.917165)
			(xy 152.662895 84.915895) (xy 152.663525 84.915265)
		)
		(stroke
			(width 0)
			(type default)
		)
		(fill yes)
		(layer "F.Cu")
	)
	(gr_poly
		(pts
			(xy 152.989315 84.455115) (xy 152.988045 84.465255) (xy 152.982345 84.472225) (xy 152.972835 84.485535)
			(xy 152.969035 84.489335) (xy 152.967765 84.491875) (xy 152.962695 84.504545) (xy 152.956985 84.511525)
			(xy 152.953825 84.514685) (xy 152.952555 84.517225) (xy 152.946845 84.522925) (xy 152.944315 84.524195)
			(xy 152.941145 84.527365) (xy 152.939875 84.529905) (xy 152.934175 84.535605) (xy 152.931635 84.536875)
			(xy 152.928465 84.540045) (xy 152.927205 84.542575) (xy 152.922765 84.547015) (xy 152.920225 84.548285)
			(xy 152.912625 84.555885) (xy 152.906285 84.558425) (xy 152.898045 84.561595) (xy 152.890435 84.567935)
			(xy 152.887265 84.571095) (xy 152.878395 84.576165) (xy 152.873325 84.581245) (xy 152.858115 84.583775)
			(xy 152.846075 84.588215) (xy 152.840365 84.590115) (xy 152.835295 84.591385) (xy 152.826425 84.592655)
			(xy 152.802335 84.593915) (xy 152.793465 84.595185) (xy 152.746565 84.593915) (xy 152.742755 84.592655)
			(xy 152.726275 84.591385) (xy 152.717405 84.587575) (xy 152.711065 84.585045) (xy 152.705995 84.583775)
			(xy 152.695215 84.581875) (xy 152.688885 84.579335) (xy 152.679375 84.573635) (xy 152.667335 84.569195)
			(xy 152.662895 84.566035) (xy 152.657825 84.560955) (xy 152.655285 84.559695) (xy 152.648315 84.553985)
			(xy 152.643885 84.549545) (xy 152.628035 84.543845) (xy 152.625505 84.541305) (xy 152.624235 84.538775)
			(xy 152.616625 84.533705) (xy 152.611555 84.528635) (xy 152.610285 84.526095) (xy 152.602685 84.518495)
			(xy 152.600145 84.512155) (xy 152.598245 84.505185) (xy 152.596345 84.503275) (xy 152.595075 84.500745)
			(xy 152.588735 84.494405) (xy 152.587465 84.491875) (xy 152.581765 84.484895) (xy 152.577325 84.480465)
			(xy 152.571625 84.464615) (xy 152.565925 84.455115) (xy 152.564655 84.446235) (xy 152.563385 84.441165)
			(xy 152.561485 84.425315) (xy 152.560215 84.420245) (xy 152.557045 84.413275) (xy 152.554515 84.404405)
			(xy 152.553245 84.395535) (xy 152.551975 84.382855) (xy 152.553245 84.353695) (xy 152.554515 84.349895)
			(xy 152.555785 84.342285) (xy 152.560855 84.330885) (xy 152.562115 84.325805) (xy 152.563385 84.313135)
			(xy 152.565285 84.301095) (xy 152.568455 84.292855) (xy 152.573525 84.281445) (xy 152.574795 84.276375)
			(xy 152.576055 84.267495) (xy 152.577325 84.262425) (xy 152.583035 84.255455) (xy 152.584935 84.253555)
			(xy 152.586205 84.251015) (xy 152.591905 84.244045) (xy 152.595705 84.240245) (xy 152.597615 84.239605)
			(xy 152.598875 84.237075) (xy 152.607115 84.228835) (xy 152.609655 84.227565) (xy 152.615995 84.219965)
			(xy 152.619795 84.216155) (xy 152.621695 84.215525) (xy 152.622965 84.212995) (xy 152.631205 84.204755)
			(xy 152.633735 84.203485) (xy 152.636905 84.199045) (xy 152.642615 84.193345) (xy 152.645145 84.192075)
			(xy 152.652755 84.184465) (xy 152.659095 84.181935) (xy 152.667335 84.178765) (xy 152.671765 84.175595)
			(xy 152.676835 84.170525) (xy 152.679375 84.169255) (xy 152.686345 84.163555) (xy 152.695855 84.157845)
			(xy 152.708535 84.156575) (xy 152.712335 84.155315) (xy 152.721205 84.151505) (xy 152.730085 84.148975)
			(xy 152.738955 84.147705) (xy 152.762405 84.145805) (xy 152.789665 84.145165) (xy 152.793465 84.146435)
			(xy 152.819455 84.148335) (xy 152.825785 84.149605) (xy 152.835925 84.153405) (xy 152.846705 84.156575)
			(xy 152.851775 84.157845) (xy 152.859385 84.159115) (xy 152.868255 84.164185) (xy 152.879665 84.169255)
			(xy 152.886005 84.171795) (xy 152.888535 84.173055) (xy 152.897415 84.179395) (xy 152.902485 84.180665)
			(xy 152.910715 84.183835) (xy 152.917695 84.190805) (xy 152.920225 84.192075) (xy 152.922765 84.194605)
			(xy 152.925295 84.195875) (xy 152.929735 84.200315) (xy 152.931005 84.202845) (xy 152.934175 84.206015)
			(xy 152.936705 84.207285) (xy 152.941145 84.211725) (xy 152.942415 84.214255) (xy 152.946845 84.218695)
			(xy 152.949385 84.219965) (xy 152.952555 84.223135) (xy 152.953825 84.225665) (xy 152.956355 84.228205)
			(xy 152.957625 84.230735) (xy 152.962695 84.235805) (xy 152.965225 84.242145) (xy 152.966495 84.247215)
			(xy 152.972205 84.254185) (xy 152.976635 84.258625) (xy 152.981715 84.267495) (xy 152.986785 84.272565)
			(xy 152.989315 84.281445) (xy 152.990575 84.292855) (xy 152.995655 84.304265) (xy 152.996915 84.309335)
			(xy 152.998185 84.318205) (xy 152.999455 84.330885) (xy 153.000725 84.354965) (xy 153.001985 84.375245)
			(xy 153.000725 84.387925) (xy 152.998815 84.417715) (xy 152.997555 84.429125) (xy 152.996285 84.434195)
			(xy 152.993745 84.440535) (xy 152.990575 84.448775) (xy 152.989315 84.453845)
		)
		(stroke
			(width 0)
			(type default)
		)
		(fill yes)
		(layer "F.Cu")
	)
	(gr_poly
		(pts
			(xy 152.369435 83.863125) (xy 152.368805 86.532145) (xy 152.369435 86.536585) (xy 152.368165 86.540385)
			(xy 152.368805 86.561305) (xy 152.368165 86.580955) (xy 152.369435 86.584755) (xy 152.368165 86.589825)
			(xy 152.366905 86.598705) (xy 152.368165 86.603775) (xy 152.368805 86.610745) (xy 152.367535 86.617085)
			(xy 152.366265 86.622155) (xy 152.364995 86.655105) (xy 152.362465 86.661445) (xy 152.353585 86.670325)
			(xy 152.347255 86.672855) (xy 152.311755 86.674125) (xy 152.307955 86.675395) (xy 152.302885 86.676665)
			(xy 152.290845 86.674755) (xy 152.287675 86.674125) (xy 152.283865 86.675395) (xy 152.274995 86.676665)
			(xy 152.262325 86.675395) (xy 152.249645 86.676665) (xy 152.223655 86.676025) (xy 152.214145 86.676665)
			(xy 152.210345 86.675395) (xy 152.203375 86.674755) (xy 152.195765 86.676025) (xy 152.188795 86.676665)
			(xy 152.184995 86.675395) (xy 152.174855 86.672855) (xy 152.143165 86.671585) (xy 152.136195 86.665885)
			(xy 152.131115 86.660815) (xy 152.128585 86.654475) (xy 152.127315 86.618985) (xy 152.126045 86.615185)
			(xy 152.124785 86.606305) (xy 152.126045 86.602505) (xy 152.127315 86.594895) (xy 152.126045 86.591095)
			(xy 152.124785 86.582215) (xy 152.126045 86.577155) (xy 152.125415 86.554965) (xy 152.126045 86.540385)
			(xy 152.124785 86.536585) (xy 152.125415 86.519475) (xy 152.124145 80.796055) (xy 152.123515 80.791615)
			(xy 152.124785 80.787815) (xy 152.123515 80.766255) (xy 152.122245 80.762455) (xy 152.120975 80.721895)
			(xy 152.118445 80.715555) (xy 152.114635 80.706685) (xy 152.113375 80.701605) (xy 152.108305 80.692735)
			(xy 152.103225 80.687665) (xy 152.101965 80.685135) (xy 152.096255 80.678155) (xy 152.093725 80.676895)
			(xy 152.088015 80.671185) (xy 152.086755 80.668655) (xy 152.083585 80.665485) (xy 152.081045 80.664215)
			(xy 152.074075 80.658505) (xy 152.070905 80.655335) (xy 152.064565 80.652805) (xy 152.057595 80.650905)
			(xy 152.041745 80.642665) (xy 152.036675 80.641395) (xy 152.026535 80.640125) (xy 152.022735 80.638865)
			(xy 152.013865 80.635065) (xy 152.008795 80.633795) (xy 151.992305 80.632525) (xy 151.962525 80.630625)
			(xy 151.910545 80.629355) (xy 151.418705 80.628085) (xy 151.410465 80.627455) (xy 151.406655 80.628725)
			(xy 151.383835 80.627455) (xy 151.380035 80.628725) (xy 151.364825 80.627455) (xy 151.361025 80.626185)
			(xy 151.330595 80.624915) (xy 151.324265 80.621115) (xy 151.317285 80.615415) (xy 151.316025 80.612875)
			(xy 151.313485 80.606535) (xy 151.312855 80.585615) (xy 151.313485 80.578645) (xy 151.312215 80.574845)
			(xy 151.310315 80.566605) (xy 151.309685 80.557095) (xy 151.310945 80.553295) (xy 151.310315 80.529845)
			(xy 151.310945 80.519065) (xy 151.309685 80.515265) (xy 151.310315 80.484205) (xy 151.309685 80.473435)
			(xy 151.310945 80.469625) (xy 151.310315 80.447445) (xy 151.311585 80.442375) (xy 151.312855 80.436035)
			(xy 151.313485 80.429065) (xy 151.312215 80.426535) (xy 151.313485 80.422725) (xy 151.314755 80.402445)
			(xy 151.319185 80.396745) (xy 151.321725 80.395475) (xy 151.324265 80.391665) (xy 151.330595 80.389135)
			(xy 151.365465 80.387235) (xy 151.370535 80.385965) (xy 151.382575 80.385335) (xy 151.386375 80.386595)
			(xy 151.409195 80.385335) (xy 151.412995 80.386595) (xy 151.429475 80.385335) (xy 152.041745 80.386595)
			(xy 152.045555 80.387865) (xy 152.081045 80.389135) (xy 152.084845 80.390405) (xy 152.089925 80.391665)
			(xy 152.096255 80.394205) (xy 152.101325 80.395475) (xy 152.119075 80.398005) (xy 152.132385 80.401175)
			(xy 152.143165 80.406885) (xy 152.149495 80.409415) (xy 152.157735 80.412585) (xy 152.162175 80.415755)
			(xy 152.168515 80.419555) (xy 152.174855 80.422095) (xy 152.183095 80.425265) (xy 152.184995 80.427165)
			(xy 152.187525 80.428435) (xy 152.201475 80.434775) (xy 152.210345 80.439845) (xy 152.216685 80.443645)
			(xy 152.223025 80.446185) (xy 152.228095 80.447445) (xy 152.235065 80.453155) (xy 152.239505 80.457585)
			(xy 152.242035 80.458855) (xy 152.247745 80.464555) (xy 152.249005 80.467095) (xy 152.250915 80.468995)
			(xy 152.253445 80.470265) (xy 152.260415 80.477235) (xy 152.261685 80.479775) (xy 152.263585 80.481675)
			(xy 152.266125 80.482935) (xy 152.273095 80.489915) (xy 152.274365 80.492445) (xy 152.276265 80.494345)
			(xy 152.278795 80.495615) (xy 152.284505 80.501325) (xy 152.285775 80.503855) (xy 152.288945 80.507025)
			(xy 152.291475 80.508295) (xy 152.295915 80.512735) (xy 152.297185 80.515265) (xy 152.304785 80.522875)
			(xy 152.307315 80.529205) (xy 152.310485 80.537445) (xy 152.313655 80.541885) (xy 152.319995 80.548225)
			(xy 152.323805 80.554565) (xy 152.330135 80.560905) (xy 152.334575 80.572945) (xy 152.336475 80.577385)
			(xy 152.342815 80.587525) (xy 152.344085 80.596395) (xy 152.345345 80.601465) (xy 152.346615 80.609075)
			(xy 152.355495 80.628085) (xy 152.357395 80.640125) (xy 152.362465 80.652805) (xy 152.363735 80.657875)
			(xy 152.364995 80.665485) (xy 152.366265 80.693375) (xy 152.367535 80.727595) (xy 152.368805 80.803655)
			(xy 152.369435 83.861855)
		)
		(stroke
			(width 0)
			(type default)
		)
		(fill yes)
		(layer "F.Cu")
	)
	(gr_poly
		(pts
			(xy 162.520115 83.294575) (xy 162.525185 83.295845) (xy 162.532785 83.303455) (xy 162.535325 83.304725)
			(xy 162.537855 83.307255) (xy 162.540395 83.308525) (xy 162.543565 83.312965) (xy 162.549265 83.318665)
			(xy 162.551805 83.319935) (xy 162.558145 83.326275) (xy 162.560675 83.327535) (xy 162.567015 83.330075)
			(xy 162.572085 83.331345) (xy 162.579055 83.337045) (xy 162.583495 83.341485) (xy 162.586035 83.342745)
			(xy 162.593005 83.349725) (xy 162.594265 83.352255) (xy 162.596175 83.354155) (xy 162.598705 83.355425)
			(xy 162.604415 83.361135) (xy 162.605675 83.363665) (xy 162.612015 83.370005) (xy 162.613285 83.372535)
			(xy 162.615825 83.378875) (xy 162.617085 83.383945) (xy 162.619625 83.386485) (xy 162.620895 83.389015)
			(xy 162.627225 83.395355) (xy 162.628495 83.397895) (xy 162.634205 83.404865) (xy 162.637375 83.408035)
			(xy 162.641805 83.420075) (xy 162.644975 83.424515) (xy 162.648775 83.428315) (xy 162.650045 83.430855)
			(xy 162.658915 83.442265) (xy 162.661455 83.444795) (xy 162.663985 83.454935) (xy 162.665255 83.465075)
			(xy 162.674135 83.484095) (xy 162.676665 83.494235) (xy 162.677935 83.503105) (xy 162.685545 83.519585)
			(xy 162.687445 83.526555) (xy 162.688715 83.540505) (xy 162.689975 83.548105) (xy 162.691875 83.555085)
			(xy 162.694415 83.561415) (xy 162.696955 83.570295) (xy 162.698215 83.582965) (xy 162.700755 83.617195)
			(xy 162.698855 83.641915) (xy 162.697585 83.657125) (xy 162.696315 83.664735) (xy 162.692515 83.674875)
			(xy 162.691245 83.679945) (xy 162.689345 83.686915) (xy 162.688075 83.699595) (xy 162.686805 83.708465)
			(xy 162.685545 83.712265) (xy 162.679205 83.726215) (xy 162.676665 83.735085) (xy 162.675395 83.745225)
			(xy 162.662725 83.771845) (xy 162.657655 83.780725) (xy 162.650045 83.797205) (xy 162.644975 83.806075)
			(xy 162.639905 83.817485) (xy 162.634835 83.826355) (xy 162.629765 83.831425) (xy 162.628495 83.833965)
			(xy 162.624065 83.839665) (xy 162.621525 83.840935) (xy 162.613285 83.849175) (xy 162.612655 83.851075)
			(xy 162.610115 83.852345) (xy 162.601875 83.860585) (xy 162.600605 83.863125) (xy 162.593005 83.869455)
			(xy 162.552435 83.910025) (xy 162.551805 83.911925) (xy 162.549265 83.913195) (xy 162.541025 83.921435)
			(xy 162.539765 83.923965) (xy 162.535325 83.927135) (xy 162.528355 83.932845) (xy 162.525185 83.936015)
			(xy 162.518845 83.938545) (xy 162.513775 83.939815) (xy 162.507435 83.943615) (xy 162.504905 83.946145)
			(xy 162.496025 83.949955) (xy 162.487785 83.953125) (xy 162.480815 83.957555) (xy 162.466875 83.963895)
			(xy 162.447855 83.972765) (xy 162.442785 83.974035) (xy 162.426305 83.975305) (xy 162.421235 83.976575)
			(xy 162.409195 83.981005) (xy 162.398415 83.984175) (xy 162.393345 83.985445) (xy 162.380675 83.986715)
			(xy 162.371795 83.987985) (xy 162.359755 83.989885) (xy 162.354685 83.991155) (xy 162.344545 83.994955)
			(xy 162.338205 83.996225) (xy 162.328065 83.997495) (xy 162.310945 83.999385) (xy 162.293835 83.997495)
			(xy 162.283695 83.996225) (xy 162.277355 83.994955) (xy 162.270385 83.991785) (xy 162.263415 83.989885)
			(xy 162.255805 83.988615) (xy 162.238695 83.986715) (xy 162.225385 83.984815) (xy 162.220315 83.983545)
			(xy 162.212075 83.980375) (xy 162.203205 83.976575) (xy 162.194325 83.975305) (xy 162.189255 83.974035)
			(xy 162.181015 83.970875) (xy 162.165175 83.963895) (xy 162.156295 83.962635) (xy 162.148695 83.961365)
			(xy 162.141715 83.955655) (xy 162.138555 83.952485) (xy 162.129675 83.947415) (xy 162.123335 83.941075)
			(xy 162.117005 83.938545) (xy 162.108765 83.935375) (xy 162.101155 83.930305) (xy 162.094185 83.927135)
			(xy 162.084045 83.923335) (xy 162.076435 83.915725) (xy 162.073905 83.914455) (xy 162.065665 83.906215)
			(xy 162.065025 83.904315) (xy 162.062495 83.903045) (xy 162.011785 83.852345) (xy 162.009255 83.851075)
			(xy 162.004185 83.843475) (xy 161.997205 83.836495) (xy 161.994675 83.830155) (xy 161.990865 83.820015)
			(xy 161.988335 83.817485) (xy 161.987065 83.814945) (xy 161.983265 83.806075) (xy 161.980095 83.797835)
			(xy 161.971855 83.789595) (xy 161.970585 83.787065) (xy 161.964255 83.778185) (xy 161.961715 83.775655)
			(xy 161.959185 83.769315) (xy 161.957915 83.760435) (xy 161.956015 83.753465) (xy 161.953475 83.747135)
			(xy 161.946505 83.731285) (xy 161.944605 83.719235) (xy 161.940795 83.709105) (xy 161.938895 83.702125)
			(xy 161.937625 83.697055) (xy 161.935725 83.667265) (xy 161.934455 83.634305) (xy 161.933825 83.598185)
			(xy 161.935095 83.594375) (xy 161.936365 83.548745) (xy 161.937625 83.544935) (xy 161.938895 83.527195)
			(xy 161.942695 83.518325) (xy 161.945235 83.509445) (xy 161.947135 83.498675) (xy 161.949675 83.492335)
			(xy 161.956645 83.477755) (xy 161.957915 83.468875) (xy 161.959815 83.460635) (xy 161.962345 83.454305)
			(xy 161.965515 83.451135) (xy 161.969315 83.442265) (xy 161.970585 83.437195) (xy 161.974395 83.430855)
			(xy 161.980725 83.424515) (xy 161.981995 83.421975) (xy 161.987705 83.413735) (xy 161.989605 83.413105)
			(xy 161.990865 83.410565) (xy 161.994675 83.401695) (xy 161.999745 83.392825) (xy 162.006085 83.386485)
			(xy 162.007345 83.383945) (xy 162.063755 83.327535) (xy 162.065665 83.326905) (xy 162.066925 83.324375)
			(xy 162.075165 83.316125) (xy 162.077705 83.314865) (xy 162.084045 83.308525) (xy 162.090385 83.305985)
			(xy 162.098625 83.302815) (xy 162.104325 83.297115) (xy 162.106865 83.295845) (xy 162.109395 83.293315)
			(xy 162.115735 83.289505) (xy 162.122075 83.283175) (xy 162.136015 83.278105) (xy 162.144885 83.271765)
			(xy 162.156935 83.267325) (xy 162.161365 83.265425) (xy 162.171505 83.259085) (xy 162.186725 83.256555)
			(xy 162.198765 83.252115) (xy 162.205735 83.248945) (xy 162.215875 83.246405) (xy 162.232355 83.245145)
			(xy 162.237425 83.243875) (xy 162.250105 83.242605) (xy 162.253905 83.241335) (xy 162.266585 83.237535)
			(xy 162.271655 83.236265) (xy 162.284335 83.234995) (xy 162.318555 83.232465) (xy 162.359755 83.235635)
			(xy 162.364825 83.236905) (xy 162.371165 83.238165) (xy 162.379405 83.241335) (xy 162.389545 83.243875)
			(xy 162.405395 83.245775) (xy 162.415535 83.248315) (xy 162.421865 83.250845) (xy 162.423775 83.252745)
			(xy 162.436445 83.256555) (xy 162.446585 83.257815) (xy 162.465605 83.266695) (xy 162.475745 83.269225)
			(xy 162.485885 83.270495) (xy 162.492855 83.276205) (xy 162.496025 83.279365) (xy 162.504905 83.284435)
			(xy 162.511235 83.290775) (xy 162.517575 83.293315) (xy 162.519475 83.293945)
		)
		(stroke
			(width 0)
			(type default)
		)
		(fill yes)
		(layer "F.Cu")
	)
	(gr_poly
		(pts
			(xy 160.919075 81.139585) (xy 160.640195 81.138315) (xy 160.636395 81.137045) (xy 160.602165 81.135775)
			(xy 160.598365 81.134515) (xy 160.590125 81.131345) (xy 160.579345 81.128175) (xy 160.569835 81.126275)
			(xy 160.559695 81.122465) (xy 160.551455 81.118035) (xy 160.541315 81.115495) (xy 160.531175 81.114225)
			(xy 160.522305 81.109155) (xy 160.508355 81.102815) (xy 160.502025 81.100285) (xy 160.493145 81.093945)
			(xy 160.479205 81.088875) (xy 160.473495 81.084435) (xy 160.472235 81.081905) (xy 160.461455 81.074925)
			(xy 160.455115 81.068595) (xy 160.450045 81.067325) (xy 160.441805 81.064155) (xy 160.433565 81.055915)
			(xy 160.427235 81.052115) (xy 160.425325 81.050215) (xy 160.424065 81.047675) (xy 160.418355 81.041975)
			(xy 160.415825 81.040705) (xy 160.412655 81.037535) (xy 160.411385 81.035005) (xy 160.405675 81.029295)
			(xy 160.403145 81.028025) (xy 160.401245 81.026125) (xy 160.399975 81.023595) (xy 160.394275 81.017885)
			(xy 160.391735 81.016615) (xy 160.388565 81.013445) (xy 160.384765 81.007115) (xy 160.378425 81.000775)
			(xy 160.375885 80.994435) (xy 160.374625 80.989365) (xy 160.365745 80.975425) (xy 160.364485 80.970355)
			(xy 160.358145 80.958945) (xy 160.353075 80.953875) (xy 160.351805 80.951335) (xy 160.346095 80.944365)
			(xy 160.341665 80.939925) (xy 160.335955 80.924085) (xy 160.330885 80.916475) (xy 160.327715 80.905695)
			(xy 160.325815 80.894925) (xy 160.323285 80.888585) (xy 160.320115 80.881615) (xy 160.317575 80.875275)
			(xy 160.316305 80.870205) (xy 160.315045 80.857535) (xy 160.313775 80.847385) (xy 160.308705 80.834715)
			(xy 160.307435 80.829645) (xy 160.305535 80.808725) (xy 160.304265 80.788445) (xy 160.303635 80.737105)
			(xy 160.304905 80.733295) (xy 160.306165 80.702875) (xy 160.307435 80.699075) (xy 160.308705 80.690205)
			(xy 160.311235 80.683865) (xy 160.313775 80.674985) (xy 160.318215 80.647735) (xy 160.320745 80.641395)
			(xy 160.326455 80.628085) (xy 160.327715 80.619215) (xy 160.329625 80.610975) (xy 160.331525 80.609075)
			(xy 160.332785 80.606535) (xy 160.337865 80.601465) (xy 160.339125 80.598925) (xy 160.344835 80.591955)
			(xy 160.346735 80.590055) (xy 160.348005 80.587525) (xy 160.353075 80.576115) (xy 160.358145 80.567235)
			(xy 160.364485 80.553295) (xy 160.368915 80.545055) (xy 160.371455 80.543785) (xy 160.373355 80.541885)
			(xy 160.374625 80.539355) (xy 160.380325 80.532375) (xy 160.387295 80.526675) (xy 160.393005 80.519705)
			(xy 160.399975 80.513995) (xy 160.405675 80.507025) (xy 160.408215 80.505755) (xy 160.412655 80.501325)
			(xy 160.413915 80.498785) (xy 160.418355 80.494345) (xy 160.420895 80.493085) (xy 160.425325 80.488645)
			(xy 160.426595 80.486105) (xy 160.429765 80.482935) (xy 160.432295 80.481675) (xy 160.436735 80.477235)
			(xy 160.438005 80.474695) (xy 160.442435 80.470265) (xy 160.444975 80.468995) (xy 160.449415 80.464555)
			(xy 160.450675 80.462025) (xy 160.453845 80.458855) (xy 160.456385 80.457585) (xy 160.458915 80.455055)
			(xy 160.461455 80.453785) (xy 160.462725 80.451255) (xy 160.465255 80.449985) (xy 160.467795 80.447445)
			(xy 160.474765 80.445545) (xy 160.482375 80.441745) (xy 160.489975 80.436675) (xy 160.500115 80.432865)
			(xy 160.506455 80.430335) (xy 160.509625 80.427165) (xy 160.512165 80.425895) (xy 160.521035 80.422095)
			(xy 160.527375 80.419555) (xy 160.529905 80.418285) (xy 160.538785 80.411955) (xy 160.550825 80.407515)
			(xy 160.557165 80.404975) (xy 160.565405 80.400545) (xy 160.570475 80.399275) (xy 160.588225 80.396745)
			(xy 160.601525 80.393575) (xy 160.607865 80.391035) (xy 160.614205 80.389765) (xy 160.631955 80.388505)
			(xy 160.653505 80.387235) (xy 160.705475 80.385965) (xy 161.068655 80.385335) (xy 161.072465 80.386595)
			(xy 161.142185 80.387865) (xy 161.145985 80.389135) (xy 161.166265 80.390405) (xy 161.175145 80.394205)
			(xy 161.184015 80.396745) (xy 161.202395 80.398645) (xy 161.207465 80.399915) (xy 161.213805 80.402445)
			(xy 161.227115 80.408145) (xy 161.235985 80.409415) (xy 161.241055 80.410685) (xy 161.249295 80.413855)
			(xy 161.251195 80.415755) (xy 161.262605 80.420825) (xy 161.270845 80.423995) (xy 161.277815 80.428435)
			(xy 161.291765 80.434775) (xy 161.298105 80.438575) (xy 161.303175 80.443645) (xy 161.305705 80.444915)
			(xy 161.315215 80.451885) (xy 161.315845 80.453785) (xy 161.318385 80.455055) (xy 161.331055 80.460125)
			(xy 161.333595 80.461395) (xy 161.341205 80.468995) (xy 161.343735 80.470265) (xy 161.348175 80.473435)
			(xy 161.349445 80.475965) (xy 161.351975 80.478505) (xy 161.352615 80.480405) (xy 161.355145 80.481675)
			(xy 161.370355 80.496885) (xy 161.372255 80.497515) (xy 161.373525 80.500055) (xy 161.376065 80.502585)
			(xy 161.376695 80.504495) (xy 161.379235 80.505755) (xy 161.381765 80.508295) (xy 161.384305 80.509565)
			(xy 161.389375 80.517165) (xy 161.396345 80.524135) (xy 161.401415 80.538085) (xy 161.407115 80.545055)
			(xy 161.410285 80.548225) (xy 161.411555 80.550765) (xy 161.417265 80.557735) (xy 161.420435 80.560905)
			(xy 161.424865 80.572945) (xy 161.428035 80.577385) (xy 161.433105 80.582445) (xy 161.434375 80.584985)
			(xy 161.440715 80.593855) (xy 161.444515 80.597665) (xy 161.447055 80.607805) (xy 161.448315 80.617945)
			(xy 161.457185 80.636955) (xy 161.459725 80.647095) (xy 161.460995 80.655975) (xy 161.467335 80.669915)
			(xy 161.469235 80.684495) (xy 161.470505 80.692105) (xy 161.471765 80.713655) (xy 161.473035 80.726325)
			(xy 161.474305 80.737735) (xy 161.475575 80.742805) (xy 161.479375 80.752945) (xy 161.482545 80.761185)
			(xy 161.483815 80.766255) (xy 161.482545 80.777665) (xy 161.476205 80.791615) (xy 161.474935 80.796685)
			(xy 161.473665 80.805555) (xy 161.472405 80.810625) (xy 161.471135 80.830905) (xy 161.469235 80.844215)
			(xy 161.466695 80.856895) (xy 161.460995 80.870205) (xy 161.459725 80.879085) (xy 161.457185 80.889225)
			(xy 161.450855 80.899365) (xy 161.448315 80.905695) (xy 161.445155 80.913935) (xy 161.442615 80.920275)
			(xy 161.440715 80.922185) (xy 161.439445 80.924715) (xy 161.435645 80.933585) (xy 161.433745 80.946895)
			(xy 161.431205 80.953235) (xy 161.424235 80.960205) (xy 161.419165 80.969085) (xy 161.412825 80.975425)
			(xy 161.407755 80.989365) (xy 161.400145 80.996975) (xy 161.398875 80.999505) (xy 161.394445 81.005205)
			(xy 161.391905 81.006475) (xy 161.335495 81.062885) (xy 161.334865 81.064785) (xy 161.332325 81.066055)
			(xy 161.329795 81.068595) (xy 161.327255 81.069855) (xy 161.320925 81.076195) (xy 161.314585 81.078735)
			(xy 161.306345 81.081905) (xy 161.298735 81.086975) (xy 161.291765 81.090145) (xy 161.283525 81.093315)
			(xy 161.276555 81.097745) (xy 161.262605 81.104085) (xy 161.251195 81.110425) (xy 161.239795 81.115495)
			(xy 161.215705 81.126905) (xy 161.203665 81.128805) (xy 161.193525 81.132605) (xy 161.187815 81.134515)
			(xy 161.178945 81.135775) (xy 161.130775 81.138315) (xy 161.030625 81.139585) (xy 160.920345 81.139585)
		)
		(stroke
			(width 0)
			(type default)
		)
		(fill yes)
		(layer "F.Cu")
	)
	(gr_poly
		(pts
			(xy 159.477765 80.386595) (xy 159.481565 80.387865) (xy 159.515795 80.389135) (xy 159.519595 80.390405)
			(xy 159.525935 80.391665) (xy 159.532265 80.394205) (xy 159.537345 80.395475) (xy 159.555085 80.398005)
			(xy 159.568395 80.401175) (xy 159.584245 80.408145) (xy 159.593115 80.409415) (xy 159.598185 80.410685)
			(xy 159.606425 80.413855) (xy 159.608325 80.415755) (xy 159.610865 80.417025) (xy 159.619735 80.420825)
			(xy 159.627975 80.423995) (xy 159.634955 80.428435) (xy 159.648895 80.434775) (xy 159.655235 80.438575)
			(xy 159.660305 80.443645) (xy 159.662835 80.444915) (xy 159.672345 80.451885) (xy 159.672975 80.453785)
			(xy 159.675515 80.455055) (xy 159.688195 80.460125) (xy 159.690725 80.461395) (xy 159.698335 80.468995)
			(xy 159.700865 80.470265) (xy 159.705305 80.473435) (xy 159.706575 80.475965) (xy 159.709105 80.478505)
			(xy 159.709745 80.480405) (xy 159.712275 80.481675) (xy 159.768685 80.538085) (xy 159.769955 80.540615)
			(xy 159.777555 80.548225) (xy 159.780095 80.554565) (xy 159.781365 80.559635) (xy 159.790235 80.573575)
			(xy 159.791505 80.578645) (xy 159.800375 80.595125) (xy 159.804185 80.604005) (xy 159.806715 80.610335)
			(xy 159.811785 80.619215) (xy 159.815595 80.628085) (xy 159.817495 80.640125) (xy 159.821295 80.650265)
			(xy 159.824465 80.657245) (xy 159.825735 80.662315) (xy 159.827005 80.671185) (xy 159.828265 80.676255)
			(xy 159.830165 80.698445) (xy 159.831435 80.703515) (xy 159.837135 80.721895) (xy 159.839035 80.737735)
			(xy 159.840305 80.760555) (xy 159.840945 80.763725) (xy 159.839675 80.767525) (xy 159.838405 80.796685)
			(xy 159.837135 80.800485) (xy 159.835865 80.809355) (xy 159.833335 80.815695) (xy 159.830795 80.824565)
			(xy 159.829535 80.829645) (xy 159.827635 80.851825) (xy 159.826365 80.859435) (xy 159.825095 80.865775)
			(xy 159.822565 80.872105) (xy 159.819395 80.879085) (xy 159.816855 80.887955) (xy 159.814955 80.898725)
			(xy 159.812425 80.905065) (xy 159.810525 80.906965) (xy 159.804185 80.920915) (xy 159.801015 80.929155)
			(xy 159.796575 80.934855) (xy 159.795305 80.937395) (xy 159.792775 80.943725) (xy 159.789605 80.951965)
			(xy 159.782625 80.958945) (xy 159.781365 80.961475) (xy 159.772485 80.972885) (xy 159.769955 80.975425)
			(xy 159.765515 80.987465) (xy 159.762345 80.991905) (xy 159.757275 80.996975) (xy 159.756005 80.999505)
			(xy 159.753475 81.002045) (xy 159.752845 81.003945) (xy 159.750305 81.005205) (xy 159.686925 81.068595)
			(xy 159.684385 81.069855) (xy 159.678045 81.076195) (xy 159.671715 81.078735) (xy 159.663475 81.081905)
			(xy 159.657765 81.087605) (xy 159.655235 81.088875) (xy 159.652695 81.091415) (xy 159.646365 81.095215)
			(xy 159.640025 81.101555) (xy 159.624175 81.107255) (xy 159.622275 81.109155) (xy 159.619735 81.110425)
			(xy 159.610865 81.114225) (xy 159.601995 81.115495) (xy 159.596915 81.116765) (xy 159.588685 81.119935)
			(xy 159.580445 81.124365) (xy 159.571565 81.126905) (xy 159.562695 81.128175) (xy 159.550655 81.132605)
			(xy 159.544945 81.134515) (xy 159.536075 81.135775) (xy 159.487905 81.138315) (xy 159.387765 81.139585)
			(xy 158.708305 81.140845) (xy 158.704495 81.142115) (xy 158.662665 81.143385) (xy 158.658865 81.144655)
			(xy 158.648715 81.145925) (xy 158.639845 81.149725) (xy 158.629705 81.152255) (xy 158.622105 81.153525)
			(xy 158.605625 81.161135) (xy 158.596745 81.163665) (xy 158.587875 81.164935) (xy 158.579635 81.168105)
			(xy 158.570125 81.173805) (xy 158.558085 81.178245) (xy 158.551115 81.182675) (xy 158.537165 81.189015)
			(xy 158.525755 81.195355) (xy 158.514345 81.200425) (xy 158.505475 81.205495) (xy 158.502945 81.208035)
			(xy 158.500405 81.209305) (xy 158.496605 81.213105) (xy 158.494065 81.214375) (xy 158.489635 81.218815)
			(xy 158.488365 81.221345) (xy 158.485195 81.224515) (xy 158.482655 81.225785) (xy 158.476955 81.231485)
			(xy 158.475685 81.234025) (xy 158.473785 81.235925) (xy 158.471245 81.237185) (xy 158.465545 81.242895)
			(xy 158.464275 81.245425) (xy 158.461105 81.248595) (xy 158.458575 81.249865) (xy 158.452865 81.255565)
			(xy 158.451605 81.258105) (xy 158.448435 81.261275) (xy 158.445895 81.262545) (xy 158.441465 81.266975)
			(xy 158.440195 81.269515) (xy 158.436395 81.273315) (xy 158.435125 81.275855) (xy 158.431325 81.279655)
			(xy 158.426885 81.291705) (xy 158.422445 81.298675) (xy 158.416105 81.312615) (xy 158.413575 81.318955)
			(xy 158.407235 81.327825) (xy 158.402795 81.339865) (xy 158.396455 81.350015) (xy 158.393285 81.356985)
			(xy 158.390115 81.365225) (xy 158.387585 81.371565) (xy 158.385685 81.373465) (xy 158.384415 81.375995)
			(xy 158.381885 81.382335) (xy 158.380615 81.391205) (xy 158.379345 81.396285) (xy 158.376175 81.404525)
			(xy 158.373005 81.415295) (xy 158.371745 81.427965) (xy 158.370475 81.444445) (xy 158.368575 81.467905)
			(xy 158.367935 81.481215) (xy 158.369205 81.485015) (xy 158.371105 81.514805) (xy 158.372375 81.528745)
			(xy 158.373645 81.536355) (xy 158.377445 81.546495) (xy 158.379345 81.553465) (xy 158.380615 81.558535)
			(xy 158.382515 81.568045) (xy 158.385055 81.574385) (xy 158.392025 81.590225) (xy 158.394555 81.605435)
			(xy 158.399625 81.614315) (xy 158.403435 81.623185) (xy 158.405965 81.629525) (xy 158.409765 81.635865)
			(xy 158.416105 81.642205) (xy 158.419915 81.648545) (xy 158.426245 81.654885) (xy 158.428785 81.661215)
			(xy 158.431955 81.669455) (xy 158.435125 81.673895) (xy 158.440195 81.678965) (xy 158.441465 81.681495)
			(xy 158.459845 81.699885) (xy 158.462375 81.701145) (xy 158.464275 81.703055) (xy 158.465545 81.705585)
			(xy 158.472515 81.712555) (xy 158.475055 81.713825) (xy 158.476955 81.715725) (xy 158.478225 81.718265)
			(xy 158.485195 81.725235) (xy 158.487725 81.726505) (xy 158.489635 81.728405) (xy 158.490895 81.730935)
			(xy 158.496605 81.736645) (xy 158.499135 81.737915) (xy 158.505475 81.744245) (xy 158.508015 81.745515)
			(xy 158.514345 81.748055) (xy 158.519425 81.749315) (xy 158.526395 81.755025) (xy 158.530835 81.759455)
			(xy 158.533365 81.760725) (xy 158.540335 81.766435) (xy 158.543505 81.769605) (xy 158.549845 81.772135)
			(xy 158.561885 81.776575) (xy 158.563785 81.778475) (xy 158.566325 81.779745) (xy 158.575195 81.783545)
			(xy 158.584075 81.784815) (xy 158.591045 81.786715) (xy 158.597385 81.789245) (xy 158.613225 81.796225)
			(xy 158.625275 81.798125) (xy 158.643645 81.803825) (xy 158.656325 81.805095) (xy 158.691185 81.806995)
			(xy 158.741895 81.808265) (xy 162.906115 81.809535) (xy 162.955545 81.810805) (xy 162.978365 81.812065)
			(xy 163.003085 81.813965) (xy 163.009425 81.816505) (xy 163.018295 81.819045) (xy 163.027175 81.820305)
			(xy 163.046825 81.822215) (xy 163.054425 81.823475) (xy 163.059495 81.824745) (xy 163.065835 81.827285)
			(xy 163.072805 81.830455) (xy 163.082945 81.832985) (xy 163.092455 81.834885) (xy 163.098795 81.837425)
			(xy 163.100695 81.839325) (xy 163.114635 81.845655) (xy 163.122875 81.848825) (xy 163.124785 81.850725)
			(xy 163.127315 81.851995) (xy 163.141255 81.858335) (xy 163.152665 81.864675) (xy 163.155205 81.867205)
			(xy 163.162175 81.869115) (xy 163.168515 81.871645) (xy 163.172955 81.874815) (xy 163.178025 81.879885)
			(xy 163.180555 81.881155) (xy 163.183095 81.883695) (xy 163.185625 81.884955) (xy 163.188795 81.889395)
			(xy 163.194495 81.895095) (xy 163.197035 81.896365) (xy 163.203375 81.902705) (xy 163.205905 81.903975)
			(xy 163.212245 81.906505) (xy 163.217315 81.907775) (xy 163.224295 81.913475) (xy 163.228725 81.917915)
			(xy 163.231265 81.919185) (xy 163.236965 81.924885) (xy 163.238235 81.927425) (xy 163.241405 81.931855)
			(xy 163.243945 81.933125) (xy 163.247115 81.938835) (xy 163.251545 81.950875) (xy 163.258515 81.957845)
			(xy 163.259785 81.960385) (xy 163.268025 81.968625) (xy 163.270555 81.969885) (xy 163.275625 81.977495)
			(xy 163.282605 81.984465) (xy 163.288305 82.000315) (xy 163.291475 82.003485) (xy 163.292745 82.006015)
			(xy 163.297815 82.017425) (xy 163.300355 82.023765) (xy 163.306685 82.032635) (xy 163.307955 82.037705)
			(xy 163.310485 82.044045) (xy 163.319365 82.063065) (xy 163.321895 82.080805) (xy 163.323805 82.091585)
			(xy 163.328235 82.106165) (xy 163.329505 82.115035) (xy 163.331405 82.138485) (xy 163.332675 82.171445)
			(xy 163.333305 82.210105) (xy 163.332045 82.213915) (xy 163.330775 82.257015) (xy 163.329505 82.260815)
			(xy 163.328235 82.281095) (xy 163.325705 82.287435) (xy 163.323165 82.296305) (xy 163.320635 82.314055)
			(xy 163.318725 82.323565) (xy 163.316195 82.329905) (xy 163.314295 82.331805) (xy 163.309225 82.344485)
			(xy 163.306055 82.352715) (xy 163.304155 82.354615) (xy 163.302885 82.357155) (xy 163.300355 82.359695)
			(xy 163.294015 82.376175) (xy 163.286405 82.383775) (xy 163.285135 82.386315) (xy 163.279435 82.393285)
			(xy 163.277535 82.395185) (xy 163.276265 82.397725) (xy 163.272465 82.406595) (xy 163.267385 82.415465)
			(xy 163.261055 82.421805) (xy 163.259785 82.424345) (xy 163.240135 82.443985) (xy 163.238235 82.444625)
			(xy 163.236965 82.447155) (xy 163.228725 82.455395) (xy 163.226825 82.456035) (xy 163.225555 82.458565)
			(xy 163.204645 82.479485) (xy 163.202105 82.480755) (xy 163.198935 82.485185) (xy 163.193235 82.490895)
			(xy 163.190695 82.492165) (xy 163.183095 82.499765) (xy 163.176755 82.502305) (xy 163.168515 82.505475)
			(xy 163.160905 82.510545) (xy 163.153935 82.513715) (xy 163.145695 82.516875) (xy 163.138725 82.521315)
			(xy 163.127315 82.526385) (xy 163.113375 82.533995) (xy 163.099425 82.540335) (xy 163.080415 82.549205)
			(xy 163.062665 82.551735) (xy 163.051895 82.553645) (xy 163.037315 82.558075) (xy 163.032245 82.559345)
			(xy 162.998645 82.561245) (xy 162.946675 82.562515) (xy 160.296025 82.563785) (xy 160.295395 82.564415)
			(xy 160.291595 82.563145) (xy 160.271305 82.564415) (xy 160.207925 82.565685) (xy 160.204125 82.566955)
			(xy 160.174965 82.568215) (xy 160.171165 82.569485) (xy 160.164825 82.572025) (xy 160.155955 82.574555)
			(xy 160.143275 82.575825) (xy 160.138205 82.577095) (xy 160.128065 82.578355) (xy 160.111585 82.585965)
			(xy 160.106515 82.587235) (xy 160.095735 82.589135) (xy 160.087495 82.592305) (xy 160.073555 82.598645)
			(xy 160.068485 82.599915) (xy 160.058345 82.601175) (xy 160.046935 82.607515) (xy 160.038065 82.611315)
			(xy 160.029825 82.614485) (xy 160.022215 82.620825) (xy 160.020315 82.622725) (xy 160.017775 82.623995)
			(xy 160.015245 82.626525) (xy 160.013345 82.627165) (xy 160.012075 82.629695) (xy 160.003835 82.637935)
			(xy 160.001305 82.639205) (xy 159.994965 82.645545) (xy 159.988625 82.648085) (xy 159.980385 82.651245)
			(xy 159.975945 82.654415) (xy 159.969605 82.660755) (xy 159.967075 82.662025) (xy 159.960105 82.668995)
			(xy 159.958835 82.671535) (xy 159.954395 82.674705) (xy 159.949955 82.679135) (xy 159.948695 82.681675)
			(xy 159.944895 82.685475) (xy 159.944255 82.687375) (xy 159.942355 82.688005) (xy 159.941085 82.690545)
			(xy 159.938555 82.696885) (xy 159.935385 82.705125) (xy 159.927145 82.713365) (xy 159.925875 82.715895)
			(xy 159.920165 82.722875) (xy 159.916995 82.726045) (xy 159.914465 82.732375) (xy 159.911295 82.740615)
			(xy 159.906225 82.748225) (xy 159.900525 82.761535) (xy 159.895455 82.770405) (xy 159.887845 82.786885)
			(xy 159.881505 82.800835) (xy 159.880245 82.805905) (xy 159.878335 82.821745) (xy 159.875805 82.847105)
			(xy 159.874535 82.854705) (xy 159.873265 82.861045) (xy 159.872005 82.866115) (xy 159.870095 82.873085)
			(xy 159.868835 82.878155) (xy 159.866295 82.893365) (xy 159.865025 82.906045) (xy 159.866295 82.914925)
			(xy 159.868195 82.926965) (xy 159.869465 82.933305) (xy 159.870735 82.938375) (xy 159.873905 82.949145)
			(xy 159.875165 82.954215) (xy 159.876435 82.963095) (xy 159.877705 82.975765) (xy 159.879605 82.987805)
			(xy 159.880875 82.992875) (xy 159.884675 83.003025) (xy 159.887845 83.011265) (xy 159.889115 83.016335)
			(xy 159.891015 83.027105) (xy 159.893545 83.033445) (xy 159.895455 83.035345) (xy 159.899255 83.044215)
			(xy 159.902425 83.052455) (xy 159.904325 83.056895) (xy 159.910665 83.063235) (xy 159.911935 83.065765)
			(xy 159.914465 83.068305) (xy 159.918265 83.074645) (xy 159.920165 83.076545) (xy 159.922075 83.077175)
			(xy 159.923335 83.079715) (xy 159.925875 83.086055) (xy 159.929045 83.094295) (xy 159.936015 83.101265)
			(xy 159.937285 83.103795) (xy 159.952495 83.119005) (xy 159.953125 83.120915) (xy 159.955665 83.122175)
			(xy 159.976585 83.143095) (xy 159.977215 83.144995) (xy 159.979755 83.146265) (xy 159.994965 83.161475)
			(xy 159.997495 83.162745) (xy 160.003835 83.169085) (xy 160.017775 83.174155) (xy 160.025385 83.181755)
			(xy 160.027915 83.183025) (xy 160.039325 83.191905) (xy 160.050735 83.196975) (xy 160.062145 83.203305)
			(xy 160.064685 83.205845) (xy 160.069755 83.207115) (xy 160.076095 83.209645) (xy 160.097635 83.219785)
			(xy 160.109045 83.221055) (xy 160.115385 83.223595) (xy 160.128065 83.227395) (xy 160.133135 83.228665)
			(xy 160.173695 83.229925) (xy 160.177505 83.231195) (xy 160.219965 83.231835) (xy 160.223135 83.231195)
			(xy 160.226945 83.232465) (xy 161.177675 83.233735) (xy 161.181475 83.234995) (xy 161.219505 83.236265)
			(xy 161.223305 83.237535) (xy 161.230285 83.239435) (xy 161.238525 83.242605) (xy 161.256275 83.245145)
			(xy 161.266415 83.246405) (xy 161.272745 83.248945) (xy 161.286695 83.255285) (xy 161.295565 83.256555)
			(xy 161.303805 83.258455) (xy 161.310145 83.260985) (xy 161.312045 83.262885) (xy 161.314585 83.264155)
			(xy 161.325995 83.269225) (xy 161.334225 83.272395) (xy 161.336135 83.274295) (xy 161.338665 83.275565)
			(xy 161.345005 83.279365) (xy 161.353245 83.282535) (xy 161.359585 83.285075) (xy 161.362755 83.288235)
			(xy 161.365285 83.289505) (xy 161.374165 83.293315) (xy 161.380495 83.295845) (xy 161.387475 83.301555)
			(xy 161.390635 83.304725) (xy 161.393175 83.305985) (xy 161.398875 83.311695) (xy 161.400145 83.314225)
			(xy 161.403315 83.317395) (xy 161.405855 83.318665) (xy 161.412825 83.324375) (xy 161.415995 83.327535)
			(xy 161.429935 83.332615) (xy 161.445785 83.348455) (xy 161.447685 83.355425) (xy 161.450215 83.361765)
			(xy 161.457185 83.368735) (xy 161.458455 83.371275) (xy 161.464165 83.378245) (xy 161.466695 83.379515)
			(xy 161.473665 83.386485) (xy 161.474305 83.388385) (xy 161.476835 83.389655) (xy 161.483815 83.396625)
			(xy 161.485075 83.399165) (xy 161.492685 83.406765) (xy 161.495225 83.413105) (xy 161.498395 83.421345)
			(xy 161.501565 83.425785) (xy 161.507895 83.432125) (xy 161.511695 83.438455) (xy 161.517405 83.445435)
			(xy 161.519305 83.451135) (xy 161.520575 83.460005) (xy 161.521845 83.467615) (xy 161.528185 83.476485)
			(xy 161.531345 83.484725) (xy 161.535155 83.494865) (xy 161.537685 83.501205) (xy 161.539585 83.506915)
			(xy 161.540855 83.511985) (xy 161.542755 83.546845) (xy 161.544655 83.622265) (xy 161.543395 83.626075)
			(xy 161.542755 83.659665) (xy 161.543395 83.671705) (xy 161.542125 83.675505) (xy 161.540225 83.710365)
			(xy 161.538955 83.716705) (xy 161.536425 83.723045) (xy 161.533255 83.733815) (xy 161.531985 83.738885)
			(xy 161.530715 83.747765) (xy 161.525645 83.756635) (xy 161.520575 83.768045) (xy 161.512965 83.781995)
			(xy 161.507895 83.793395) (xy 161.500295 83.807345) (xy 161.496485 83.816215) (xy 161.490155 83.827625)
			(xy 161.483815 83.833965) (xy 161.482545 83.836495) (xy 161.475575 83.843475) (xy 161.473035 83.844735)
			(xy 161.469865 83.849175) (xy 161.465425 83.853615) (xy 161.462895 83.854885) (xy 161.459725 83.858045)
			(xy 161.458455 83.860585) (xy 161.452755 83.866285) (xy 161.450215 83.867555) (xy 161.448315 83.869455)
			(xy 161.447055 83.871995) (xy 161.440075 83.878965) (xy 161.437545 83.880235) (xy 161.435645 83.882135)
			(xy 161.434375 83.884665) (xy 161.415995 83.903045) (xy 161.413455 83.904315) (xy 161.411555 83.906215)
			(xy 161.410285 83.908755) (xy 161.404585 83.914455) (xy 161.402045 83.915725) (xy 161.394445 83.923335)
			(xy 161.388105 83.925865) (xy 161.379865 83.929035) (xy 161.375425 83.932205) (xy 161.374165 83.934745)
			(xy 161.371625 83.936015) (xy 161.360215 83.944885) (xy 161.356415 83.948685) (xy 161.340565 83.954395)
			(xy 161.338665 83.956295) (xy 161.327255 83.961365) (xy 161.322185 83.962635) (xy 161.310145 83.964535)
			(xy 161.291765 83.974035) (xy 161.279085 83.979105) (xy 161.267685 83.984175) (xy 161.251835 83.986085)
			(xy 161.237885 83.987345) (xy 161.226475 83.988615) (xy 161.209995 83.991155) (xy 161.204925 83.992415)
			(xy 161.199225 83.994325) (xy 161.186555 83.995585) (xy 161.138375 83.998125) (xy 161.092105 83.998755)
			(xy 161.090205 83.998125) (xy 161.086405 83.999385) (xy 159.535435 84.000025) (xy 159.532265 83.999385)
			(xy 159.528465 84.000655) (xy 159.472695 84.001925) (xy 159.468885 84.003195) (xy 159.443535 84.004465)
			(xy 159.432125 84.009535) (xy 159.425785 84.012065) (xy 159.414375 84.018405) (xy 159.402975 84.023475)
			(xy 159.389025 84.031085) (xy 159.377615 84.036155) (xy 159.363675 84.043765) (xy 159.354795 84.047565)
			(xy 159.343395 84.053905) (xy 159.338325 84.058975) (xy 159.335785 84.060235) (xy 159.331345 84.063405)
			(xy 159.330085 84.065945) (xy 159.323105 84.072915) (xy 159.320575 84.074185) (xy 159.312965 84.081785)
			(xy 159.306625 84.084325) (xy 159.298385 84.087495) (xy 159.287615 84.098265) (xy 159.285715 84.098905)
			(xy 159.284445 84.101435) (xy 159.280645 84.110315) (xy 159.275575 84.119185) (xy 159.269235 84.125525)
			(xy 159.265435 84.131865) (xy 159.259095 84.138195) (xy 159.254025 84.152145) (xy 159.249585 84.157845)
			(xy 159.247685 84.158485) (xy 159.246415 84.161015) (xy 159.237545 84.172425) (xy 159.235005 84.174965)
			(xy 159.232465 84.181295) (xy 159.229305 84.189535) (xy 159.222335 84.202845) (xy 159.221065 84.207915)
			(xy 159.219795 84.216795) (xy 159.215365 84.228835) (xy 159.209655 84.242145) (xy 159.207755 84.259255)
			(xy 159.206485 84.266865) (xy 159.205215 84.271935) (xy 159.201415 84.282075) (xy 159.200145 84.287145)
			(xy 159.198875 84.294755) (xy 159.196345 84.325175) (xy 159.195715 84.329615) (xy 159.196975 84.333415)
			(xy 159.198875 84.360665) (xy 159.200145 84.368275) (xy 159.201415 84.373345) (xy 159.203955 84.379685)
			(xy 159.205855 84.386655) (xy 159.207125 84.391725) (xy 159.208385 84.404405) (xy 159.209655 84.409475)
			(xy 159.210925 84.418345) (xy 159.218525 84.434825) (xy 159.222965 84.454475) (xy 159.231205 84.470325)
			(xy 159.234375 84.478565) (xy 159.237545 84.482995) (xy 159.240075 84.485535) (xy 159.241345 84.488065)
			(xy 159.243875 84.490605) (xy 159.245145 84.493135) (xy 159.247685 84.495675) (xy 159.248955 84.498205)
			(xy 159.255285 84.504545) (xy 159.257195 84.511525) (xy 159.259725 84.517855) (xy 159.266695 84.524835)
			(xy 159.267965 84.527365) (xy 159.270505 84.529905) (xy 159.271765 84.532435) (xy 159.276205 84.535605)
			(xy 159.283175 84.542575) (xy 159.283815 84.544475) (xy 159.286345 84.545745) (xy 159.307265 84.566665)
			(xy 159.308535 84.569195) (xy 159.312965 84.572365) (xy 159.319935 84.579335) (xy 159.320575 84.581245)
			(xy 159.323105 84.582505) (xy 159.331345 84.590745) (xy 159.331985 84.592655) (xy 159.334515 84.593915)
			(xy 159.338325 84.597725) (xy 159.340855 84.598985) (xy 159.347195 84.605325) (xy 159.363035 84.611025)
			(xy 159.364945 84.612935) (xy 159.367475 84.614195) (xy 159.370015 84.616735) (xy 159.375085 84.618005)
			(xy 159.383955 84.621805) (xy 159.396635 84.629415) (xy 159.402975 84.631945) (xy 159.411205 84.635115)
			(xy 159.424515 84.642085) (xy 159.429595 84.643355) (xy 159.440365 84.645255) (xy 159.450505 84.649065)
			(xy 159.465085 84.653495) (xy 159.473955 84.654765) (xy 159.501845 84.656035) (xy 159.505645 84.657295)
			(xy 159.524035 84.659195) (xy 159.531635 84.660465) (xy 159.541775 84.663005) (xy 159.555725 84.664265)
			(xy 159.612135 84.667435) (xy 159.731295 84.668705) (xy 160.649065 84.669975) (xy 160.652875 84.671245)
			(xy 160.687095 84.672515) (xy 160.693435 84.675045) (xy 160.702305 84.678845) (xy 160.711185 84.680115)
			(xy 160.716255 84.681385) (xy 160.723225 84.683285) (xy 160.737805 84.690255) (xy 160.746675 84.692795)
			(xy 160.756815 84.694065) (xy 160.765695 84.699135) (xy 160.779635 84.705475) (xy 160.785975 84.708005)
			(xy 160.794845 84.714345) (xy 160.806885 84.718785) (xy 160.813225 84.722585) (xy 160.814495 84.725115)
			(xy 160.820195 84.729555) (xy 160.822735 84.730825) (xy 160.827175 84.735265) (xy 160.828435 84.737795)
			(xy 160.831605 84.740965) (xy 160.834145 84.742235) (xy 160.841115 84.747935) (xy 160.845555 84.752375)
			(xy 160.855055 84.754275) (xy 160.859495 84.756175) (xy 160.861395 84.758075) (xy 160.862665 84.763145)
			(xy 160.864565 84.771385) (xy 160.867735 84.775825) (xy 160.874705 84.777725) (xy 160.881045 84.778995)
			(xy 160.885485 84.782165) (xy 160.888015 84.791035) (xy 160.889285 84.796105) (xy 160.896895 84.803715)
			(xy 160.898165 84.806245) (xy 160.903865 84.813225) (xy 160.910835 84.818925) (xy 160.916535 84.827165)
			(xy 160.919075 84.828435) (xy 160.920975 84.830335) (xy 160.923515 84.836675) (xy 160.924785 84.841745)
			(xy 160.929855 84.850615) (xy 160.932385 84.853145) (xy 160.934925 84.859485) (xy 160.938095 84.867725)
			(xy 160.944425 84.877875) (xy 160.947595 84.884845) (xy 160.952035 84.896885) (xy 160.953935 84.898785)
			(xy 160.959005 84.910195) (xy 160.960275 84.919065) (xy 160.961545 84.924135) (xy 160.967885 84.940615)
			(xy 160.969145 84.945685) (xy 160.971045 84.962805) (xy 160.972315 84.972945) (xy 160.973585 84.990695)
			(xy 160.974855 85.005905) (xy 160.976115 85.012245) (xy 160.979925 85.022385) (xy 160.982455 85.028715)
			(xy 160.984355 85.035695) (xy 160.983095 85.049635) (xy 160.978025 85.061045) (xy 160.974215 85.076255)
			(xy 160.972315 85.106045) (xy 160.969775 85.126325) (xy 160.968515 85.137735) (xy 160.961545 85.154855)
			(xy 160.960275 85.163725) (xy 160.959005 85.168795) (xy 160.955835 85.177035) (xy 160.948865 85.192885)
			(xy 160.946965 85.204925) (xy 160.944425 85.211265) (xy 160.938725 85.220765) (xy 160.933655 85.234715)
			(xy 160.927945 85.241685) (xy 160.924785 85.244855) (xy 160.923515 85.247395) (xy 160.917805 85.254365)
			(xy 160.914635 85.257535) (xy 160.912105 85.263865) (xy 160.908935 85.272105) (xy 160.900695 85.280345)
			(xy 160.896895 85.286685) (xy 160.894995 85.288585) (xy 160.892455 85.289855) (xy 160.886755 85.295555)
			(xy 160.885485 85.298095) (xy 160.883585 85.299995) (xy 160.881045 85.301265) (xy 160.872805 85.309505)
			(xy 160.872175 85.311405) (xy 160.869635 85.312675) (xy 160.860125 85.322175) (xy 160.859495 85.324085)
			(xy 160.856955 85.325345) (xy 160.849985 85.332325) (xy 160.848725 85.334855) (xy 160.846825 85.336755)
			(xy 160.844285 85.338025) (xy 160.838585 85.343725) (xy 160.837315 85.346265) (xy 160.834145 85.349435)
			(xy 160.831605 85.350705) (xy 160.825905 85.356405) (xy 160.824635 85.358945) (xy 160.821465 85.362115)
			(xy 160.818935 85.363375) (xy 160.811955 85.369085) (xy 160.808785 85.372255) (xy 160.796745 85.376685)
			(xy 160.792305 85.378595) (xy 160.789775 85.381125) (xy 160.787245 85.382395) (xy 160.778365 85.386195)
			(xy 160.772025 85.388735) (xy 160.763155 85.393805) (xy 160.754285 85.397605) (xy 160.745405 85.398875)
			(xy 160.738435 85.400775) (xy 160.732095 85.403305) (xy 160.726395 85.405215) (xy 160.721325 85.406475)
			(xy 160.704845 85.407745) (xy 160.665545 85.409015) (xy 160.633855 85.410285) (xy 156.894935 85.410915)
			(xy 156.889225 85.410285) (xy 156.885425 85.411555) (xy 156.864505 85.410915) (xy 156.842325 85.411555)
			(xy 156.839785 85.410285) (xy 156.835985 85.411555) (xy 156.786545 85.415355) (xy 156.778945 85.416625)
			(xy 156.771335 85.421695) (xy 156.768805 85.422955) (xy 156.761825 85.428665) (xy 156.754225 85.445145)
			(xy 156.752325 85.474935) (xy 156.751055 85.492685) (xy 156.750425 85.512325) (xy 156.751695 85.514865)
			(xy 156.750425 85.518665) (xy 156.749785 85.580145) (xy 156.750425 85.831775) (xy 156.749155 85.835575)
			(xy 156.747885 85.942055) (xy 156.746615 85.945865) (xy 156.745355 85.977555) (xy 156.739015 85.991495)
			(xy 156.735845 85.999735) (xy 156.733305 86.004805) (xy 156.730775 86.006075) (xy 156.723805 86.013045)
			(xy 156.722535 86.015585) (xy 156.715555 86.018755) (xy 156.703515 86.023195) (xy 156.696545 86.026355)
			(xy 156.687675 86.027625) (xy 156.652815 86.029525) (xy 156.600835 86.030795) (xy 155.743275 86.031425)
			(xy 155.739475 86.030165) (xy 155.671025 86.028895) (xy 155.667215 86.027625) (xy 155.645665 86.026355)
			(xy 155.631725 86.020025) (xy 155.623485 86.016855) (xy 155.616515 86.009875) (xy 155.613975 86.008615)
			(xy 155.607005 86.002905) (xy 155.601935 85.995305) (xy 155.600665 85.992765) (xy 155.596865 85.983895)
			(xy 155.596225 85.964245) (xy 155.596865 85.954735) (xy 155.595595 85.950935) (xy 155.594325 85.945865)
			(xy 155.594965 85.926215) (xy 155.593055 85.912905) (xy 155.594325 85.909105) (xy 155.593695 85.886915)
			(xy 155.594325 85.871065) (xy 155.593055 85.867265) (xy 155.594325 85.848255) (xy 155.593055 85.844455)
			(xy 155.591795 85.702475) (xy 155.590525 85.698665) (xy 155.589255 85.661915) (xy 155.584185 85.650505)
			(xy 155.581645 85.644165) (xy 155.580385 85.639095) (xy 155.574045 85.630215) (xy 155.564535 85.620705)
			(xy 155.559465 85.619445) (xy 155.556295 85.618805) (xy 155.551225 85.620075) (xy 155.543625 85.626415)
			(xy 155.536015 85.634025) (xy 155.533485 85.640355) (xy 155.529045 85.652405) (xy 155.525875 85.660645)
			(xy 155.524605 85.665715) (xy 155.523335 85.705005) (xy 155.522075 85.708815) (xy 155.520805 85.808955)
			(xy 155.520165 85.908465) (xy 155.520805 85.919245) (xy 155.519535 85.923045) (xy 155.520165 85.943955)
			(xy 155.518905 85.950295) (xy 155.517635 85.970585) (xy 155.516365 85.987055) (xy 155.506865 86.002905)
			(xy 155.502425 86.007345) (xy 155.499885 86.008615) (xy 155.492285 86.016215) (xy 155.485945 86.018755)
			(xy 155.473895 86.023195) (xy 155.466925 86.026355) (xy 155.461855 86.027625) (xy 155.421925 86.029525)
			(xy 155.371225 86.030795) (xy 155.025785 86.031425) (xy 155.021985 86.030165) (xy 154.952265 86.028895)
			(xy 154.948465 86.027625) (xy 154.928175 86.026355) (xy 154.916765 86.021285) (xy 154.908535 86.018115)
			(xy 154.901555 86.013685) (xy 154.896485 86.008615) (xy 154.893955 86.007345) (xy 154.886985 86.000375)
			(xy 154.885715 85.997835) (xy 154.880645 85.990225) (xy 154.879375 85.985155) (xy 154.877475 85.951565)
			(xy 154.876205 85.945225) (xy 154.875575 85.935725) (xy 154.876835 85.931915) (xy 154.875575 85.909105)
			(xy 154.876835 85.905295) (xy 154.875575 85.885015) (xy 154.874935 85.572545) (xy 154.875575 85.557965)
			(xy 154.874305 85.554165) (xy 154.875575 85.532605) (xy 154.874305 85.528805) (xy 154.873035 85.519935)
			(xy 154.871135 85.483805) (xy 154.869865 85.476195) (xy 154.866695 85.469225) (xy 154.860995 85.453385)
			(xy 154.859095 85.451475) (xy 154.857825 85.448945) (xy 154.851485 85.442605) (xy 154.850215 85.440065)
			(xy 154.844515 85.434365) (xy 154.838175 85.430565) (xy 154.834375 85.426765) (xy 154.828035 85.424225)
			(xy 154.809655 85.421055) (xy 154.805215 85.417885) (xy 154.793805 85.412815) (xy 154.782405 85.414085)
			(xy 154.773525 85.420425) (xy 154.767185 85.422955) (xy 154.758945 85.426125) (xy 154.753245 85.431835)
			(xy 154.750705 85.433095) (xy 154.748175 85.435635) (xy 154.745635 85.436905) (xy 154.741205 85.441335)
			(xy 154.739935 85.443875) (xy 154.736765 85.447045) (xy 154.734225 85.448305) (xy 154.729795 85.452745)
			(xy 154.724725 85.461625) (xy 154.722185 85.467955) (xy 154.720915 85.473035) (xy 154.722185 85.478105)
			(xy 154.720915 85.490775) (xy 154.718385 85.522465) (xy 154.717115 85.526275) (xy 154.718385 85.535145)
			(xy 154.717745 85.556065) (xy 154.718385 85.570635) (xy 154.717115 85.574445) (xy 154.717745 85.590285)
			(xy 154.716485 85.672685) (xy 154.715845 85.677125) (xy 154.717115 85.680925) (xy 154.715845 85.697405)
			(xy 154.713945 85.747475) (xy 154.712675 85.757615) (xy 154.710145 85.763955) (xy 154.705705 85.774725)
			(xy 154.704435 85.779805) (xy 154.698735 85.786775) (xy 154.695565 85.789945) (xy 154.694295 85.792475)
			(xy 154.688595 85.799445) (xy 154.677185 85.808325) (xy 154.654365 85.818465) (xy 154.644225 85.820995)
			(xy 154.603025 85.822905) (xy 154.598595 85.823535) (xy 154.594785 85.822265) (xy 154.578305 85.823535)
			(xy 154.447735 85.824805) (xy 154.416055 85.823535) (xy 154.374845 85.822905) (xy 154.369145 85.823535)
			(xy 154.365345 85.822265) (xy 154.324145 85.820365) (xy 154.319075 85.819095) (xy 154.305765 85.813395)
			(xy 154.297525 85.810225) (xy 154.295625 85.808325) (xy 154.293085 85.807055) (xy 154.286745 85.800715)
			(xy 154.284215 85.799445) (xy 154.278505 85.793745) (xy 154.277245 85.791205) (xy 154.270905 85.784875)
			(xy 154.269635 85.782335) (xy 154.265835 85.773465) (xy 154.262665 85.765225) (xy 154.259495 85.758255)
			(xy 154.258225 85.745575) (xy 154.255695 85.660645) (xy 154.254425 85.541485) (xy 154.253155 85.428665)
			(xy 154.248725 85.424225) (xy 154.240485 85.422325) (xy 154.230345 85.418525) (xy 154.223365 85.415355)
			(xy 154.189775 85.413455) (xy 154.169495 85.412185) (xy 154.092165 85.410915) (xy 153.554055 85.410285)
			(xy 153.550245 85.411555) (xy 153.456445 85.412815) (xy 153.452635 85.414085) (xy 153.421575 85.415985)
			(xy 153.415245 85.418525) (xy 153.408275 85.421695) (xy 153.400035 85.423595) (xy 153.395595 85.425495)
			(xy 153.392425 85.428665) (xy 153.391155 85.437535) (xy 153.390525 85.795645) (xy 153.391155 85.811495)
			(xy 153.389895 85.815295) (xy 153.391155 85.834315) (xy 153.389895 85.838115) (xy 153.390525 85.859025)
			(xy 153.389255 85.864095) (xy 153.387985 85.871705) (xy 153.387355 85.877405) (xy 153.388625 85.879945)
			(xy 153.387355 85.883745) (xy 153.386085 85.904035) (xy 153.380385 85.911005) (xy 153.375315 85.916075)
			(xy 153.366435 85.918605) (xy 153.334115 85.920505) (xy 153.327775 85.921775) (xy 153.322075 85.922415)
			(xy 153.318265 85.921145) (xy 153.310025 85.920505) (xy 153.299885 85.921775) (xy 153.297985 85.922415)
			(xy 153.294185 85.921145) (xy 153.270735 85.921775) (xy 153.253615 85.921145) (xy 153.249815 85.922415)
			(xy 153.233335 85.921145) (xy 153.229535 85.922415) (xy 152.676205 85.921775) (xy 152.665435 85.922415)
			(xy 152.661625 85.921145) (xy 152.640715 85.921775) (xy 152.621065 85.921145) (xy 152.618525 85.922415)
			(xy 152.614725 85.921145) (xy 152.606485 85.920505) (xy 152.596345 85.921775) (xy 152.590635 85.922415)
			(xy 152.586835 85.921145) (xy 152.577965 85.919875) (xy 152.548175 85.917975) (xy 152.541835 85.915445)
			(xy 152.532965 85.906565) (xy 152.530425 85.900225) (xy 152.529155 85.864735) (xy 152.527895 85.860925)
			(xy 152.526625 85.855855) (xy 152.527895 85.839385) (xy 152.526625 85.826705) (xy 152.527895 85.817825)
			(xy 152.526625 85.801345) (xy 152.527895 85.791205) (xy 152.526625 85.787405) (xy 152.526625 85.611205)
			(xy 152.526625 85.609935) (xy 152.527255 85.524365) (xy 152.526625 85.509785) (xy 152.527895 85.505985)
			(xy 152.526625 85.485705) (xy 152.527895 85.481905) (xy 152.527255 85.460985) (xy 152.528525 85.455915)
			(xy 152.529795 85.449575) (xy 152.531065 85.417885) (xy 152.537395 85.407745) (xy 152.541835 85.400775)
			(xy 152.543735 85.398875) (xy 152.552615 85.393805) (xy 152.561485 85.389995) (xy 152.583665 85.389365)
			(xy 152.588105 85.389995) (xy 152.591905 85.388735) (xy 152.601415 85.386825) (xy 152.610925 85.386195)
			(xy 152.614725 85.387465) (xy 152.637545 85.386195) (xy 152.641345 85.387465) (xy 152.661625 85.386195)
			(xy 152.668595 85.386825) (xy 153.053965 85.385565) (xy 153.058405 85.383665) (xy 153.060305 85.381755)
			(xy 153.061575 85.376685) (xy 153.062835 85.367815) (xy 153.061575 84.834135) (xy 153.057135 84.828435)
			(xy 153.048265 84.827165) (xy 152.678745 84.826525) (xy 152.664165 84.827165) (xy 152.660355 84.825895)
			(xy 152.639445 84.826525) (xy 152.623595 84.825895) (xy 152.619795 84.827165) (xy 152.610925 84.825895)
			(xy 152.590005 84.826525) (xy 152.583665 84.825265) (xy 152.562115 84.823995) (xy 152.546905 84.822725)
			(xy 152.539935 84.818295) (xy 152.531695 84.810055) (xy 152.530425 84.801175) (xy 152.527895 84.764415)
			(xy 152.526625 84.760615) (xy 152.527895 84.735265) (xy 152.526625 84.731455) (xy 152.527895 84.711175)
			(xy 152.529155 84.707375) (xy 152.531065 84.675045) (xy 152.534225 84.670605) (xy 152.536135 84.667435)
			(xy 152.538665 84.666175) (xy 152.542465 84.662365) (xy 152.548805 84.659835) (xy 152.582395 84.657935)
			(xy 152.587465 84.656665) (xy 152.598245 84.656035) (xy 152.602045 84.657295) (xy 152.624235 84.656665)
			(xy 152.636275 84.657295) (xy 152.640075 84.656035) (xy 152.652115 84.656665) (xy 152.654025 84.656035)
			(xy 152.655285 84.657295) (xy 152.659095 84.656035) (xy 153.055865 84.654765) (xy 153.060305 84.651595)
			(xy 153.062835 84.641455) (xy 153.061575 84.103975) (xy 153.057135 84.098265) (xy 153.048265 84.097005)
			(xy 152.662265 84.096365) (xy 152.650215 84.097005) (xy 152.646415 84.095735) (xy 152.626765 84.096365)
			(xy 152.619165 84.095095) (xy 152.618525 84.094465) (xy 152.614725 84.095735) (xy 152.602045 84.097005)
			(xy 152.598245 84.095735) (xy 152.588105 84.093195) (xy 152.556415 84.091925) (xy 152.553875 84.089395)
			(xy 152.551345 84.088125) (xy 152.540565 84.081155) (xy 152.539305 84.078615) (xy 152.532965 84.069745)
			(xy 152.530425 84.063405) (xy 152.528525 84.029815) (xy 152.527255 84.022205) (xy 152.526625 84.006365)
			(xy 152.527895 84.002555) (xy 152.526625 83.977205) (xy 152.527895 83.973405) (xy 152.529155 83.956925)
			(xy 152.531695 83.930305) (xy 152.542465 83.919525) (xy 152.552615 83.916995) (xy 152.559585 83.917625)
			(xy 152.581135 83.916365) (xy 152.586205 83.915095) (xy 152.600785 83.914455) (xy 152.604585 83.915725)
			(xy 152.621065 83.914455) (xy 153.054595 83.913195) (xy 153.060305 83.908755) (xy 153.061575 83.903685)
			(xy 153.062835 83.894805) (xy 153.061575 83.361135) (xy 153.059035 83.358595) (xy 153.058405 83.356695)
			(xy 153.049525 83.354155) (xy 152.640715 83.353525) (xy 152.624865 83.354155) (xy 152.621065 83.352895)
			(xy 152.599515 83.354155) (xy 152.593175 83.351625) (xy 152.557685 83.350355) (xy 152.548805 83.344015)
			(xy 152.542465 83.340215) (xy 152.539305 83.337045) (xy 152.538035 83.334515) (xy 152.531695 83.324375)
			(xy 152.530425 83.319295) (xy 152.528525 83.293315) (xy 152.527255 83.280635) (xy 152.526625 83.253385)
			(xy 152.527895 83.249575) (xy 152.529155 83.216615) (xy 152.530425 83.212815) (xy 152.531695 83.200145)
			(xy 152.538035 83.186195) (xy 152.539935 83.177955) (xy 152.541835 83.176055) (xy 152.542465 83.174155)
			(xy 152.548805 83.171615) (xy 153.057135 83.170355) (xy 153.060305 83.167185) (xy 153.061575 83.162105)
			(xy 153.062835 83.153235) (xy 153.062617 83.060695) (xy 153.841175 83.060695) (xy 153.843075 83.146265)
			(xy 153.844345 83.172885) (xy 153.845615 83.194435) (xy 153.846875 83.204575) (xy 153.848145 83.209645)
			(xy 153.849415 83.215985) (xy 153.850675 83.223595) (xy 153.852585 83.240705) (xy 153.853845 83.249575)
			(xy 153.855115 83.269865) (xy 153.858285 83.288235) (xy 153.860185 83.295215) (xy 153.865255 83.315495)
			(xy 153.866525 83.328175) (xy 153.867795 83.342115) (xy 153.870325 83.348455) (xy 153.874135 83.362395)
			(xy 153.875395 83.367475) (xy 153.877935 83.382685) (xy 153.879835 83.398525) (xy 153.881105 83.404865)
			(xy 153.882375 83.409935) (xy 153.886805 83.424515) (xy 153.888075 83.429585) (xy 153.890605 83.447335)
			(xy 153.892515 83.461905) (xy 153.893775 83.468245) (xy 153.897585 83.478385) (xy 153.899485 83.485365)
			(xy 153.902015 83.495505) (xy 153.903285 83.508175) (xy 153.905185 83.516415) (xy 153.909625 83.527195)
			(xy 153.913425 83.536065) (xy 153.914695 83.544935) (xy 153.915965 83.550005) (xy 153.919135 83.558245)
			(xy 153.924835 83.571565) (xy 153.927375 83.580435) (xy 153.928645 83.589305) (xy 153.936245 83.605785)
			(xy 153.938785 83.614665) (xy 153.941315 83.626075) (xy 153.947655 83.640015) (xy 153.950185 83.648885)
			(xy 153.951455 83.653955) (xy 153.953355 83.662195) (xy 153.959695 83.676145) (xy 153.961595 83.681845)
			(xy 153.964135 83.691985) (xy 153.965405 83.699595) (xy 153.971735 83.709735) (xy 153.974905 83.717975)
			(xy 153.981245 83.731915) (xy 153.986955 83.745225) (xy 153.988855 83.756005) (xy 153.992025 83.764245)
			(xy 154.000895 83.783255) (xy 154.011035 83.804805) (xy 154.012305 83.813685) (xy 154.014205 83.820655)
			(xy 154.019905 83.831425) (xy 154.023715 83.840305) (xy 154.085825 83.965795) (xy 154.089635 83.972135)
			(xy 154.095975 83.978475) (xy 154.097235 83.981005) (xy 154.102945 83.987985) (xy 154.104845 83.989885)
			(xy 154.106105 83.992415) (xy 154.111185 84.003825) (xy 154.116255 84.012705) (xy 154.122595 84.026645)
			(xy 154.128925 84.038055) (xy 154.133995 84.049465) (xy 154.139065 84.058335) (xy 154.145405 84.064675)
			(xy 154.146675 84.067205) (xy 154.152375 84.074185) (xy 154.155545 84.077355) (xy 154.158085 84.083685)
			(xy 154.159355 84.088765) (xy 154.168225 84.102705) (xy 154.169495 84.107775) (xy 154.175835 84.119185)
			(xy 154.180905 84.124255) (xy 154.182175 84.126785) (xy 154.197375 84.141995) (xy 154.198645 84.144535)
			(xy 154.202455 84.148335) (xy 154.203715 84.150875) (xy 154.206255 84.157215) (xy 154.212595 84.168625)
			(xy 154.218935 84.174965) (xy 154.220195 84.177495) (xy 154.224005 84.181295) (xy 154.225265 84.183835)
			(xy 154.229075 84.187635) (xy 154.233505 84.199675) (xy 154.239845 84.207285) (xy 154.243015 84.211725)
			(xy 154.245555 84.214255) (xy 154.246185 84.216155) (xy 154.248725 84.217425) (xy 154.256965 84.225665)
			(xy 154.258225 84.228205) (xy 154.263295 84.233275) (xy 154.264565 84.235805) (xy 154.268375 84.244675)
			(xy 154.269635 84.248485) (xy 154.275345 84.255455) (xy 154.278505 84.258625) (xy 154.279775 84.261155)
			(xy 154.307665 84.289045) (xy 154.308935 84.291585) (xy 154.312735 84.295385) (xy 154.314005 84.297925)
			(xy 154.319075 84.310595) (xy 154.325415 84.316935) (xy 154.326685 84.319475) (xy 154.332385 84.326445)
			(xy 154.339355 84.332145) (xy 154.345065 84.339125) (xy 154.352035 84.344825) (xy 154.353305 84.347365)
			(xy 154.357745 84.351795) (xy 154.360275 84.353065) (xy 154.365975 84.358775) (xy 154.367245 84.361305)
			(xy 154.369145 84.363205) (xy 154.371685 84.364475) (xy 154.535845 84.528635) (xy 154.537115 84.531165)
			(xy 154.539015 84.533075) (xy 154.541545 84.534335) (xy 154.547255 84.540045) (xy 154.548515 84.542575)
			(xy 154.552955 84.547015) (xy 154.555485 84.548285) (xy 154.558655 84.551455) (xy 154.559925 84.553985)
			(xy 154.565635 84.559695) (xy 154.568165 84.560955) (xy 154.571335 84.564125) (xy 154.572605 84.566665)
			(xy 154.577045 84.571095) (xy 154.579575 84.572365) (xy 154.584015 84.576805) (xy 154.585285 84.579335)
			(xy 154.588455 84.582505) (xy 154.590985 84.583775) (xy 154.593525 84.586315) (xy 154.596055 84.587575)
			(xy 154.601125 84.592655) (xy 154.607465 84.595185) (xy 154.612535 84.596455) (xy 154.615065 84.598985)
			(xy 154.617605 84.600255) (xy 154.620135 84.602785) (xy 154.622675 84.604055) (xy 154.639155 84.620535)
			(xy 154.641695 84.621805) (xy 154.648025 84.628145) (xy 154.650565 84.629415) (xy 154.656905 84.631945)
			(xy 154.661975 84.633215) (xy 154.664515 84.635755) (xy 154.667045 84.637015) (xy 154.672115 84.642085)
			(xy 154.674645 84.643355) (xy 154.684155 84.652865) (xy 154.684795 84.654765) (xy 154.687325 84.656035)
			(xy 154.694295 84.661735) (xy 154.698735 84.666175) (xy 154.705705 84.668075) (xy 154.712045 84.670605)
			(xy 154.715215 84.673775) (xy 154.717745 84.675045) (xy 154.722825 84.680115) (xy 154.725355 84.681385)
			(xy 154.730425 84.686455) (xy 154.732965 84.687725) (xy 154.735495 84.690255) (xy 154.741835 84.692795)
			(xy 154.750075 84.695965) (xy 154.754515 84.700405) (xy 154.757045 84.701665) (xy 154.773525 84.718145)
			(xy 154.776065 84.719415) (xy 154.782405 84.725755) (xy 154.791275 84.729555) (xy 154.796345 84.730825)
			(xy 154.805215 84.737165) (xy 154.811555 84.739695) (xy 154.819795 84.742865) (xy 154.827405 84.749205)
			(xy 154.829305 84.751105) (xy 154.831835 84.752375) (xy 154.838815 84.758075) (xy 154.841985 84.761245)
			(xy 154.844515 84.762515) (xy 154.853385 84.766315) (xy 154.867335 84.773925) (xy 154.878745 84.778995)
			(xy 154.890145 84.785335) (xy 154.899025 84.789135) (xy 154.910435 84.795475) (xy 154.915505 84.800545)
			(xy 154.918035 84.801815) (xy 154.925005 84.807515) (xy 154.929445 84.811955) (xy 154.937685 84.815125)
			(xy 154.944025 84.817655) (xy 154.953535 84.823365) (xy 154.959875 84.825895) (xy 155.065085 84.877875)
			(xy 155.084105 84.886745) (xy 155.095505 84.888015) (xy 155.122135 84.900685) (xy 155.141145 84.909565)
			(xy 155.146215 84.910825) (xy 155.159525 84.913995) (xy 155.188045 84.927305) (xy 155.204525 84.934915)
			(xy 155.215295 84.936815) (xy 155.220365 84.938085) (xy 155.227345 84.941255) (xy 155.229875 84.942525)
			(xy 155.238755 84.946325) (xy 155.256505 84.950125) (xy 155.270445 84.956465) (xy 155.283125 84.960265)
			(xy 155.290725 84.961535) (xy 155.297065 84.964065) (xy 155.311005 84.970405) (xy 155.316075 84.971675)
			(xy 155.324955 84.972945) (xy 155.331285 84.975475) (xy 155.345235 84.981815) (xy 155.355375 84.984355)
			(xy 155.364885 84.986255) (xy 155.381995 84.993225) (xy 155.392135 84.995765) (xy 155.406715 84.997665)
			(xy 155.416855 85.000195) (xy 155.423195 85.002735) (xy 155.433975 85.005905) (xy 155.451715 85.008435)
			(xy 155.463765 85.010335) (xy 155.473895 85.011605) (xy 155.478975 85.012875) (xy 155.487215 85.016045)
			(xy 155.495455 85.017945) (xy 155.501785 85.019215) (xy 155.509395 85.020475) (xy 155.519535 85.021745)
			(xy 155.536015 85.024285) (xy 155.541085 85.025545) (xy 155.549325 85.028715) (xy 155.557565 85.030625)
			(xy 155.563905 85.031885) (xy 155.577845 85.033155) (xy 155.591795 85.035695) (xy 155.596865 85.036955)
			(xy 155.603205 85.038225) (xy 155.610175 85.040125) (xy 155.620315 85.042665) (xy 155.632995 85.043935)
			(xy 155.655175 85.045835) (xy 155.666585 85.047105) (xy 155.683065 85.049635) (xy 155.695735 85.052175)
			(xy 155.707145 85.053435) (xy 155.735035 85.054705) (xy 155.751515 85.055975) (xy 155.821235 85.057245)
			(xy 156.033565 85.057875) (xy 156.037375 85.056605) (xy 156.121035 85.055345) (xy 156.124835 85.054075)
			(xy 156.160335 85.052805) (xy 156.164135 85.051535) (xy 156.172375 85.049635) (xy 156.198365 85.046465)
			(xy 156.207235 85.045195) (xy 156.223715 85.043935) (xy 156.238925 85.042665) (xy 156.242725 85.041395)
			(xy 156.247795 85.040125) (xy 156.256675 85.037595) (xy 156.263645 85.035695) (xy 156.269985 85.034425)
			(xy 156.287095 85.032525) (xy 156.299135 85.030625) (xy 156.304205 85.029355) (xy 156.311185 85.027455)
			(xy 156.317525 85.024915) (xy 156.326395 85.023645) (xy 156.331465 85.022385) (xy 156.347305 85.020475)
			(xy 156.354915 85.019215) (xy 156.361255 85.017945) (xy 156.371395 85.015415) (xy 156.382175 85.012245)
			(xy 156.387245 85.010975) (xy 156.404985 85.008435) (xy 156.419565 85.006535) (xy 156.425905 85.005265)
			(xy 156.432245 85.002735) (xy 156.446815 84.998295) (xy 156.451895 84.997035) (xy 156.467735 84.995125)
			(xy 156.472805 84.993865) (xy 156.482945 84.990055) (xy 156.493725 84.985625) (xy 156.511465 84.981815)
			(xy 156.525415 84.975475) (xy 156.531755 84.972945) (xy 156.540625 84.971675) (xy 156.545695 84.970405)
			(xy 156.559645 84.964065) (xy 156.565975 84.961535) (xy 156.580555 84.958365) (xy 156.590695 84.954565)
			(xy 156.597665 84.951395) (xy 156.604005 84.948855) (xy 156.614785 84.946955) (xy 156.619855 84.945685)
			(xy 156.632535 84.939355) (xy 156.637605 84.938085) (xy 156.644575 84.936185) (xy 156.657885 84.933015)
			(xy 156.667385 84.927305) (xy 156.675625 84.924135) (xy 156.682605 84.920965) (xy 156.701615 84.912095)
			(xy 156.714295 84.910825) (xy 156.725705 84.904495) (xy 156.737115 84.899415) (xy 156.743445 84.896885)
			(xy 156.762465 84.888015) (xy 156.771335 84.886745) (xy 156.778305 84.884845) (xy 156.791615 84.877875)
			(xy 156.797955 84.875335) (xy 156.862605 84.842375) (xy 156.871485 84.838575) (xy 156.887965 84.829695)
			(xy 156.896835 84.825895) (xy 156.910775 84.818295) (xy 156.919655 84.814485) (xy 156.931055 84.808155)
			(xy 156.937395 84.801815) (xy 156.943735 84.798005) (xy 156.948805 84.792935) (xy 156.957675 84.789135)
			(xy 156.964015 84.786595) (xy 156.971625 84.781525) (xy 156.980495 84.777725) (xy 156.986835 84.775195)
			(xy 156.993815 84.769485) (xy 156.995715 84.767585) (xy 156.998245 84.766315) (xy 157.000785 84.763785)
			(xy 157.003315 84.762515) (xy 157.009655 84.756175) (xy 157.022325 84.751105) (xy 157.024865 84.749835)
			(xy 157.035005 84.743495) (xy 157.047055 84.739065) (xy 157.057195 84.732725) (xy 157.064165 84.729555)
			(xy 157.072405 84.726385) (xy 157.074305 84.724485) (xy 157.076835 84.723215) (xy 157.083175 84.716885)
			(xy 157.085715 84.715615) (xy 157.102195 84.699135) (xy 157.104725 84.697865) (xy 157.107265 84.695325)
			(xy 157.113605 84.692795) (xy 157.121845 84.689625) (xy 157.128815 84.682655) (xy 157.131345 84.681385)
			(xy 157.142755 84.672515) (xy 157.145295 84.669975) (xy 157.157335 84.665535) (xy 157.161775 84.662365)
			(xy 157.166845 84.657295) (xy 157.169375 84.656035) (xy 157.184585 84.640825) (xy 157.187125 84.639555)
			(xy 157.192195 84.634485) (xy 157.198535 84.631945) (xy 157.206775 84.628775) (xy 157.208675 84.626875)
			(xy 157.211205 84.625605) (xy 157.217545 84.619275) (xy 157.220085 84.618005) (xy 157.228325 84.609765)
			(xy 157.229595 84.607225) (xy 157.234025 84.604055) (xy 157.237195 84.600885) (xy 157.238465 84.598355)
			(xy 157.241635 84.595185) (xy 157.244175 84.593915) (xy 157.247975 84.590115) (xy 157.250505 84.588845)
			(xy 157.254315 84.585045) (xy 157.268255 84.579975) (xy 157.274595 84.573635) (xy 157.277125 84.572365)
			(xy 157.284095 84.566665) (xy 157.285365 84.564125) (xy 157.291075 84.558425) (xy 157.293605 84.557155)
			(xy 157.296775 84.553985) (xy 157.298045 84.551455) (xy 157.303745 84.545745) (xy 157.306285 84.544475)
			(xy 157.308185 84.542575) (xy 157.309455 84.540045) (xy 157.316425 84.533075) (xy 157.318955 84.531805)
			(xy 157.322765 84.528005) (xy 157.325295 84.526735) (xy 157.327835 84.524195) (xy 157.339875 84.519765)
			(xy 157.344315 84.516595) (xy 157.349385 84.511525) (xy 157.351915 84.510255) (xy 157.358895 84.503275)
			(xy 157.360155 84.500745) (xy 157.366495 84.494405) (xy 157.367765 84.491875) (xy 157.370295 84.485535)
			(xy 157.371565 84.480465) (xy 157.377275 84.473495) (xy 157.386145 84.464615) (xy 157.392485 84.462085)
			(xy 157.400725 84.458915) (xy 157.405165 84.455745) (xy 157.410235 84.450675) (xy 157.412765 84.449405)
			(xy 157.419735 84.442435) (xy 157.421005 84.439895) (xy 157.428615 84.432295) (xy 157.431145 84.422145)
			(xy 157.434955 84.415815) (xy 157.436845 84.413915) (xy 157.441925 84.412645) (xy 157.448895 84.410745)
			(xy 157.450795 84.408845) (xy 157.453325 84.407575) (xy 157.458405 84.402505) (xy 157.460935 84.401235)
			(xy 157.469175 84.392995) (xy 157.470445 84.390465) (xy 157.476785 84.384125) (xy 157.479315 84.377785)
			(xy 157.482485 84.369545) (xy 157.486925 84.361305) (xy 157.485655 84.356235) (xy 157.479955 84.354335)
			(xy 157.472345 84.355605) (xy 157.467275 84.360665) (xy 157.464735 84.361935) (xy 157.462205 84.364475)
			(xy 157.459665 84.365745) (xy 157.456495 84.368905) (xy 157.455235 84.371445) (xy 157.449525 84.377155)
			(xy 157.446995 84.378415) (xy 157.443825 84.381585) (xy 157.442555 84.384125) (xy 157.435585 84.391095)
			(xy 157.433045 84.392365) (xy 157.431145 84.394265) (xy 157.429875 84.396795) (xy 157.412765 84.413915)
			(xy 157.410865 84.414545) (xy 157.409595 84.417085) (xy 157.401355 84.425315) (xy 157.398825 84.426585)
			(xy 157.395655 84.429755) (xy 157.394385 84.432295) (xy 157.387415 84.439265) (xy 157.384875 84.440535)
			(xy 157.382975 84.442435) (xy 157.381705 84.444965) (xy 157.353185 84.473495) (xy 157.350655 84.474765)
			(xy 157.347485 84.477925) (xy 157.346215 84.480465) (xy 157.340515 84.486165) (xy 157.337975 84.487435)
			(xy 157.334805 84.490605) (xy 157.333535 84.493135) (xy 157.327835 84.498845) (xy 157.325295 84.500115)
			(xy 157.322765 84.502645) (xy 157.320225 84.503915) (xy 157.315155 84.508985) (xy 157.306285 84.511525)
			(xy 157.299945 84.515325) (xy 157.293605 84.521665) (xy 157.291075 84.522925) (xy 157.286635 84.526095)
			(xy 157.285365 84.528635) (xy 157.234665 84.579335) (xy 157.234025 84.581245) (xy 157.231495 84.582505)
			(xy 157.227695 84.586315) (xy 157.225155 84.587575) (xy 157.220085 84.592655) (xy 157.217545 84.593915)
			(xy 157.211205 84.596455) (xy 157.206135 84.597725) (xy 157.202335 84.601525) (xy 157.200435 84.602155)
			(xy 157.199805 84.604055) (xy 157.197265 84.605325) (xy 157.194725 84.607865) (xy 157.192195 84.609125)
			(xy 157.186495 84.614835) (xy 157.185225 84.617365) (xy 157.182055 84.620535) (xy 157.179525 84.621805)
			(xy 157.174455 84.626875) (xy 157.171915 84.628145) (xy 157.169375 84.630675) (xy 157.164305 84.631945)
			(xy 157.156065 84.635115) (xy 157.149095 84.642085) (xy 157.146565 84.643355) (xy 157.139585 84.649065)
			(xy 157.136415 84.652235) (xy 157.133885 84.653495) (xy 157.125015 84.657295) (xy 157.116135 84.662365)
			(xy 157.109795 84.668705) (xy 157.107265 84.669975) (xy 157.090785 84.686455) (xy 157.088245 84.687725)
			(xy 157.085715 84.690255) (xy 157.079375 84.692795) (xy 157.071135 84.695965) (xy 157.064165 84.702935)
			(xy 157.061625 84.704205) (xy 157.054655 84.709905) (xy 157.052755 84.711805) (xy 157.050215 84.713075)
			(xy 157.047685 84.715615) (xy 157.035645 84.720045) (xy 157.031205 84.723215) (xy 157.027405 84.727025)
			(xy 157.024865 84.728285) (xy 157.022325 84.730825) (xy 157.019795 84.732095) (xy 157.013455 84.738425)
			(xy 157.010915 84.739695) (xy 157.002055 84.743495) (xy 156.977965 84.754905) (xy 156.969085 84.759975)
			(xy 156.929795 84.778995) (xy 156.923455 84.782795) (xy 156.918385 84.787865) (xy 156.915845 84.789135)
			(xy 156.913315 84.791665) (xy 156.910775 84.792935) (xy 156.906975 84.796745) (xy 156.904435 84.798005)
			(xy 156.901905 84.800545) (xy 156.893665 84.803715) (xy 156.887325 84.806245) (xy 156.879085 84.811955)
			(xy 156.872745 84.814485) (xy 156.864505 84.817655) (xy 156.856905 84.822725) (xy 156.849925 84.825895)
			(xy 156.841685 84.829065) (xy 156.831555 84.835405) (xy 156.824575 84.838575) (xy 156.818245 84.841105)
			(xy 156.806835 84.847445) (xy 156.795425 84.852515) (xy 156.773875 84.862655) (xy 156.761825 84.864555)
			(xy 156.755495 84.867095) (xy 156.722535 84.883575) (xy 156.706685 84.890545) (xy 156.687675 84.899415)
			(xy 156.676265 84.900685) (xy 156.659785 84.908295) (xy 156.653445 84.910825) (xy 156.644575 84.912095)
			(xy 156.628725 84.917795) (xy 156.615415 84.923505) (xy 156.606545 84.924775) (xy 156.601475 84.926035)
			(xy 156.583725 84.933645) (xy 156.577385 84.936185) (xy 156.565345 84.938085) (xy 156.559005 84.940615)
			(xy 156.543165 84.947595) (xy 156.523515 84.952025) (xy 156.517805 84.955195) (xy 156.511465 84.957735)
			(xy 156.502595 84.960265) (xy 156.497525 84.961535) (xy 156.490555 84.963435) (xy 156.484215 84.965975)
			(xy 156.477245 84.967875) (xy 156.476605 84.968505) (xy 156.469635 84.970405) (xy 156.464565 84.971675)
			(xy 156.448085 84.972945) (xy 156.443015 84.974215) (xy 156.430975 84.976115) (xy 156.425905 84.977385)
			(xy 156.419565 84.979915) (xy 156.408795 84.983085) (xy 156.403725 84.984355) (xy 156.394845 84.985625)
			(xy 156.382805 84.987525) (xy 156.368855 84.992595) (xy 156.361885 84.994495) (xy 156.351745 84.997035)
			(xy 156.333365 85.000195) (xy 156.328295 85.001465) (xy 156.321955 85.004005) (xy 156.316885 85.005265)
			(xy 156.309285 85.006535) (xy 156.299135 85.007805) (xy 156.291535 85.009075) (xy 156.280125 85.010335)
			(xy 156.254775 85.014145) (xy 156.247795 85.016045) (xy 156.238925 85.017315) (xy 156.233855 85.018575)
			(xy 156.211035 85.019845) (xy 156.207235 85.021115) (xy 156.164765 85.023015) (xy 156.152095 85.024285)
			(xy 156.140685 85.025545) (xy 156.133075 85.026815) (xy 156.126735 85.028085) (xy 156.116595 85.029355)
			(xy 156.101385 85.030625) (xy 156.081105 85.031885) (xy 156.036735 85.033155) (xy 156.025965 85.033785)
			(xy 156.022155 85.032525) (xy 155.990465 85.033785) (xy 155.827575 85.033155) (xy 155.823135 85.033785)
			(xy 155.819335 85.032525) (xy 155.815525 85.033785) (xy 155.795255 85.032525) (xy 155.759755 85.031255)
			(xy 155.755955 85.029985) (xy 155.730595 85.028715) (xy 155.726795 85.027455) (xy 155.717925 85.026185)
			(xy 155.712855 85.024915) (xy 155.692565 85.023645) (xy 155.671655 85.021745) (xy 155.646295 85.020475)
			(xy 155.636155 85.019215) (xy 155.619685 85.017945) (xy 155.605735 85.015415) (xy 155.598765 85.013505)
			(xy 155.568345 85.009705) (xy 155.541725 85.005905) (xy 155.536655 85.004635) (xy 155.527775 85.002095)
			(xy 155.517635 84.999565) (xy 155.505595 84.997665) (xy 155.488475 84.995765) (xy 155.475165 84.992595)
			(xy 155.468195 84.989425) (xy 155.455525 84.985625) (xy 155.447285 84.983715) (xy 155.442215 84.982455)
			(xy 155.435235 84.979285) (xy 155.428895 84.976745) (xy 155.413685 84.974215) (xy 155.401005 84.972945)
			(xy 155.392135 84.971675) (xy 155.383905 84.969775) (xy 155.369955 84.964705) (xy 155.359175 84.961535)
			(xy 155.350935 84.959635) (xy 155.345865 84.958365) (xy 155.338895 84.955195) (xy 155.327485 84.950125)
			(xy 155.315445 84.948225) (xy 155.305305 84.944425) (xy 155.291995 84.938715) (xy 155.286925 84.937445)
			(xy 155.273615 84.934285) (xy 155.259665 84.927945) (xy 155.248895 84.924775) (xy 155.239385 84.922875)
			(xy 155.233045 84.920335) (xy 155.219735 84.914635) (xy 155.209595 84.912095) (xy 155.201995 84.910825)
			(xy 155.172835 84.896885) (xy 155.156355 84.889285) (xy 155.147485 84.888015) (xy 155.142415 84.886745)
			(xy 155.118325 84.875335) (xy 155.111985 84.872795) (xy 155.095505 84.865195) (xy 155.090435 84.863925)
			(xy 155.080935 84.862025) (xy 155.074595 84.859485) (xy 155.065085 84.853785) (xy 155.056845 84.850615)
			(xy 155.050505 84.848075) (xy 155.042895 84.843005) (xy 155.036565 84.840475) (xy 155.022625 84.834135)
			(xy 155.020715 84.832235) (xy 155.018185 84.830965) (xy 155.006775 84.825895) (xy 154.995365 84.819555)
			(xy 154.983955 84.814485) (xy 154.970005 84.806885) (xy 154.958605 84.801815) (xy 154.952265 84.798005)
			(xy 154.945295 84.792305) (xy 154.939585 84.787865) (xy 154.937055 84.786595) (xy 154.930715 84.780265)
			(xy 154.923745 84.778365) (xy 154.916135 84.774555) (xy 154.906635 84.768855) (xy 154.900295 84.766315)
			(xy 154.871135 84.752375) (xy 154.868605 84.751105) (xy 154.866065 84.748565) (xy 154.863525 84.747305)
			(xy 154.858455 84.742235) (xy 154.855925 84.740965) (xy 154.848955 84.735265) (xy 154.845785 84.732095)
			(xy 154.839445 84.729555) (xy 154.834375 84.728285) (xy 154.827405 84.722585) (xy 154.824235 84.719415)
			(xy 154.821695 84.718145) (xy 154.814725 84.712445) (xy 154.811555 84.709275) (xy 154.809015 84.708005)
			(xy 154.796345 84.702935) (xy 154.793805 84.701665) (xy 154.784935 84.695325) (xy 154.779865 84.694065)
			(xy 154.768455 84.687725) (xy 154.761485 84.682015) (xy 154.757045 84.678845) (xy 154.751975 84.673775)
			(xy 154.749445 84.672515) (xy 154.738035 84.667435) (xy 154.735495 84.666175) (xy 154.728525 84.660465)
			(xy 154.724085 84.657295) (xy 154.708875 84.642085) (xy 154.706345 84.640825) (xy 154.700005 84.634485)
			(xy 154.691135 84.631945) (xy 154.682255 84.626875) (xy 154.677185 84.621805) (xy 154.674645 84.620535)
			(xy 154.667675 84.613565) (xy 154.666415 84.611025) (xy 154.664515 84.609125) (xy 154.661975 84.607865)
			(xy 154.659435 84.605325) (xy 154.656905 84.604055) (xy 154.650565 84.597725) (xy 154.641695 84.595185)
			(xy 154.635355 84.591385) (xy 154.631545 84.587575) (xy 154.629015 84.586315) (xy 154.626475 84.583775)
			(xy 154.623945 84.582505) (xy 154.622045 84.580605) (xy 154.620775 84.578075) (xy 154.599865 84.557155)
			(xy 154.597955 84.556525) (xy 154.596695 84.553985) (xy 154.564365 84.521665) (xy 154.561825 84.520395)
			(xy 154.555485 84.514055) (xy 154.552955 84.512785) (xy 154.549155 84.511525) (xy 154.540915 84.508355)
			(xy 154.533305 84.502015) (xy 154.528875 84.498845) (xy 154.397665 84.367645) (xy 154.396405 84.365105)
			(xy 154.391335 84.360035) (xy 154.388795 84.353695) (xy 154.386895 84.346725) (xy 154.384995 84.344825)
			(xy 154.383725 84.342285) (xy 154.377385 84.335955) (xy 154.376115 84.333415) (xy 154.343795 84.301095)
			(xy 154.341895 84.300455) (xy 154.340625 84.297925) (xy 154.323515 84.280805) (xy 154.320975 84.279545)
			(xy 154.315275 84.273835) (xy 154.314005 84.271305) (xy 154.311465 84.268765) (xy 154.310205 84.266235)
			(xy 154.306395 84.262425) (xy 154.305135 84.259895) (xy 154.302595 84.253555) (xy 154.301325 84.248485)
			(xy 154.293725 84.240875) (xy 154.292455 84.238345) (xy 154.286745 84.231375) (xy 154.284215 84.230105)
			(xy 154.277245 84.223135) (xy 154.275975 84.220595) (xy 154.270905 84.215525) (xy 154.269635 84.212995)
			(xy 154.267105 84.206655) (xy 154.263935 84.198415) (xy 154.256965 84.191435) (xy 154.255695 84.188905)
			(xy 154.239215 84.172425) (xy 154.237945 84.169895) (xy 154.234145 84.166085) (xy 154.232875 84.163555)
			(xy 154.230345 84.157215) (xy 154.225265 84.148335) (xy 154.221465 84.144535) (xy 154.220195 84.141995)
			(xy 154.217665 84.139465) (xy 154.216395 84.136935) (xy 154.210055 84.130595) (xy 154.208785 84.128055)
			(xy 154.206255 84.121715) (xy 154.203085 84.113485) (xy 154.199915 84.109045) (xy 154.194845 84.101435)
			(xy 154.192945 84.094465) (xy 154.191045 84.090025) (xy 154.185345 84.083055) (xy 154.182175 84.079885)
			(xy 154.180905 84.077355) (xy 154.178365 84.074815) (xy 154.177105 84.072275) (xy 154.172025 84.067205)
			(xy 154.169495 84.060865) (xy 154.168225 84.055805) (xy 154.162525 84.048835) (xy 154.159355 84.045665)
			(xy 154.158085 84.043125) (xy 154.152375 84.036155) (xy 154.150475 84.034255) (xy 154.149215 84.031715)
			(xy 154.146675 84.029185) (xy 154.145405 84.024115) (xy 154.123855 83.982275) (xy 154.120055 83.973405)
			(xy 154.114985 83.964535) (xy 154.109915 83.959465) (xy 154.108645 83.956925) (xy 154.102945 83.949955)
			(xy 154.101045 83.948055) (xy 154.099775 83.945515) (xy 154.094705 83.934105) (xy 154.091081 83.927765)
			(xy 154.401475 83.927765) (xy 154.402745 83.931575) (xy 154.404005 83.984815) (xy 154.405275 83.988615)
			(xy 154.406545 84.007625) (xy 154.412885 84.021575) (xy 154.414145 84.026645) (xy 154.420485 84.035525)
			(xy 154.424295 84.039325) (xy 154.425555 84.041855) (xy 154.432525 84.048835) (xy 154.435065 84.050095)
			(xy 154.436965 84.052005) (xy 154.438235 84.054535) (xy 154.445205 84.061505) (xy 154.447735 84.062775)
			(xy 154.450905 84.067205) (xy 154.456615 84.072915) (xy 154.459145 84.074185) (xy 154.461055 84.076085)
			(xy 154.462315 84.078615) (xy 154.469295 84.085595) (xy 154.471825 84.086855) (xy 154.473725 84.088765)
			(xy 154.474995 84.091295) (xy 154.481965 84.098265) (xy 154.484505 84.099535) (xy 154.487675 84.103975)
			(xy 154.493375 84.109675) (xy 154.495915 84.110945) (xy 154.499085 84.115385) (xy 154.506055 84.122355)
			(xy 154.508585 84.123625) (xy 154.511755 84.128055) (xy 154.517465 84.133765) (xy 154.519995 84.135025)
			(xy 154.521895 84.136935) (xy 154.523165 84.139465) (xy 154.530145 84.146435) (xy 154.532675 84.147705)
			(xy 154.534575 84.149605) (xy 154.535845 84.152145) (xy 154.542815 84.159115) (xy 154.545355 84.160385)
			(xy 154.548515 84.164815) (xy 154.554225 84.170525) (xy 154.556755 84.171795) (xy 154.558655 84.173695)
			(xy 154.559925 84.176225) (xy 154.561825 84.179395) (xy 154.564365 84.180665) (xy 154.578305 84.189535)
			(xy 154.622045 84.191435) (xy 154.629645 84.192705) (xy 154.646765 84.193345) (xy 154.650565 84.192075)
			(xy 154.659435 84.193345) (xy 155.271715 84.192075) (xy 155.274885 84.188905) (xy 155.277415 84.178765)
			(xy 155.276785 84.062775) (xy 155.277415 84.052005) (xy 155.276145 84.048195) (xy 155.276785 84.026015)
			(xy 155.275515 84.018405) (xy 155.274245 84.000655) (xy 155.272975 83.984175) (xy 155.272345 83.979745)
			(xy 155.273615 83.975935) (xy 155.272345 83.970875) (xy 155.271075 83.967065) (xy 155.265375 83.960095)
			(xy 155.262835 83.957555) (xy 155.256505 83.955025) (xy 155.215295 83.953125) (xy 155.198185 83.951225)
			(xy 155.183615 83.951855) (xy 154.840075 83.950585) (xy 154.765285 83.949315) (xy 154.731055 83.948055)
			(xy 154.703175 83.946785) (xy 154.698105 83.945515) (xy 154.691765 83.942985) (xy 154.683525 83.939815)
			(xy 154.678455 83.938545) (xy 154.670215 83.934105) (xy 154.668945 83.929035) (xy 154.669037 83.850445)
			(xy 155.447285 83.850445) (xy 155.448545 83.854245) (xy 155.447915 83.877695) (xy 155.448545 83.891005)
			(xy 155.447285 83.894805) (xy 155.447915 83.911925) (xy 155.447285 84.180025) (xy 155.448545 84.183835)
			(xy 155.449815 84.188905) (xy 155.452985 84.192075) (xy 155.458055 84.193345) (xy 155.697645 84.192075)
			(xy 155.700805 84.188905) (xy 155.703345 84.178765) (xy 155.703975 83.953755) (xy 155.703345 83.944245)
			(xy 155.704615 83.940445) (xy 155.705885 83.885935) (xy 155.707145 83.882135) (xy 155.708415 83.868195)
			(xy 155.713485 83.856785) (xy 155.714755 83.851715) (xy 155.717295 83.845375) (xy 155.720455 83.842205)
			(xy 155.725535 83.840935) (xy 155.737575 83.836495) (xy 155.743905 83.833965) (xy 155.748985 83.832695)
			(xy 155.776865 83.831425) (xy 155.812365 83.830155) (xy 155.885885 83.828895) (xy 155.970185 83.828255)
			(xy 155.973985 83.829525) (xy 156.079205 83.830795) (xy 156.083005 83.832065) (xy 156.112155 83.833325)
			(xy 156.126105 83.839665) (xy 156.134345 83.841565) (xy 156.138785 83.844735) (xy 156.141955 83.851715)
			(xy 156.143855 83.859955) (xy 156.149555 83.873265) (xy 156.151455 83.911925) (xy 156.152725 83.962635)
			(xy 156.153995 84.183195) (xy 156.155265 84.188265) (xy 156.159065 84.192075) (xy 156.164135 84.193345)
			(xy 156.403725 84.192075) (xy 156.406895 84.188905) (xy 156.408155 84.183835) (xy 156.408795 84.107145)
			(xy 156.408155 84.102705) (xy 156.409425 84.098905) (xy 156.408155 84.090025) (xy 156.409425 84.039325)
			(xy 156.409425 83.377605) (xy 156.409425 83.376345) (xy 156.408155 83.363665) (xy 156.406895 83.277465)
			(xy 156.405625 83.273665) (xy 156.404355 83.239435) (xy 156.399285 83.228025) (xy 156.398015 83.222955)
			(xy 156.395485 83.216615) (xy 156.394215 83.214085) (xy 156.387875 83.207745) (xy 156.386605 83.205215)
			(xy 156.380905 83.198245) (xy 156.373925 83.192535) (xy 156.368225 83.185565) (xy 156.361255 83.179855)
			(xy 156.355545 83.172885) (xy 156.348575 83.167185) (xy 156.342875 83.160205) (xy 156.340335 83.158945)
			(xy 156.335905 83.154505) (xy 156.334635 83.151975) (xy 156.330195 83.147535) (xy 156.327655 83.146265)
			(xy 156.323225 83.141825) (xy 156.321955 83.139295) (xy 156.318785 83.136125) (xy 156.316255 83.134855)
			(xy 156.311815 83.130415) (xy 156.310545 83.127885) (xy 156.306115 83.123445) (xy 156.303575 83.122175)
			(xy 156.299135 83.117745) (xy 156.297875 83.115205) (xy 156.293435 83.110775) (xy 156.290895 83.109505)
			(xy 156.286465 83.105065) (xy 156.285195 83.102535) (xy 156.282025 83.099365) (xy 156.279495 83.098095)
			(xy 156.275055 83.093655) (xy 156.273785 83.091125) (xy 156.269345 83.086685) (xy 156.266815 83.085415)
			(xy 156.262375 83.080985) (xy 156.261105 83.078445) (xy 156.256675 83.074005) (xy 156.254135 83.072745)
			(xy 156.250965 83.069575) (xy 156.249695 83.067035) (xy 156.245265 83.062605) (xy 156.242725 83.061335)
			(xy 156.24183 83.060695) (xy 156.567885 83.060695) (xy 156.569145 84.188905) (xy 156.572315 84.192075)
			(xy 156.577385 84.193345) (xy 156.746615 84.192705) (xy 156.763735 84.193345) (xy 156.767535 84.192075)
			(xy 156.780205 84.190805) (xy 156.815075 84.188905) (xy 156.819505 84.187005) (xy 156.829015 84.177495)
			(xy 156.830285 84.172425) (xy 156.832185 84.133765) (xy 156.834715 84.113485) (xy 156.834085 84.092565)
			(xy 156.835355 84.088765) (xy 156.834085 84.084955) (xy 156.834715 84.060235) (xy 156.833455 83.974035)
			(xy 156.832185 83.957555) (xy 156.830915 83.936015) (xy 156.829645 83.920795) (xy 156.828385 83.915725)
			(xy 156.825845 83.909385) (xy 156.822675 83.898615) (xy 156.823945 83.885935) (xy 156.834085 83.864385)
			(xy 156.835985 83.847275) (xy 156.839155 83.842835) (xy 156.846125 83.840935) (xy 156.976065 83.841565)
			(xy 156.991905 83.840935) (xy 156.995715 83.842205) (xy 157.017255 83.840935) (xy 157.023595 83.843475)
			(xy 157.059725 83.845375) (xy 157.067335 83.850445) (xy 157.070505 83.853615) (xy 157.073035 83.854885)
			(xy 157.076205 83.858045) (xy 157.078745 83.866925) (xy 157.083815 83.875795) (xy 157.090155 83.882135)
			(xy 157.091415 83.884665) (xy 157.097125 83.891635) (xy 157.100295 83.894805) (xy 157.102825 83.901145)
			(xy 157.104095 83.906215) (xy 157.112965 83.920165) (xy 157.117405 83.932205) (xy 157.120575 83.936645)
			(xy 157.125645 83.941715) (xy 157.126915 83.944245) (xy 157.132615 83.951225) (xy 157.137055 83.955655)
			(xy 157.142755 83.971505) (xy 157.145925 83.974675) (xy 157.147195 83.977205) (xy 157.150995 83.986085)
			(xy 157.154165 83.994325) (xy 157.162405 84.002555) (xy 157.166205 84.008895) (xy 157.172545 84.015235)
			(xy 157.176355 84.024115) (xy 157.177615 84.029185) (xy 157.183955 84.038055) (xy 157.185225 84.040595)
			(xy 157.187755 84.046925) (xy 157.190925 84.055165) (xy 157.195995 84.062775) (xy 157.199165 84.069745)
			(xy 157.202335 84.077985) (xy 157.205505 84.082425) (xy 157.211845 84.088765) (xy 157.215645 84.095095)
			(xy 157.221985 84.101435) (xy 157.226425 84.113485) (xy 157.232765 84.123625) (xy 157.235935 84.131865)
			(xy 157.242265 84.143265) (xy 157.247335 84.148335) (xy 157.248605 84.150875) (xy 157.254315 84.157845)
			(xy 157.257475 84.161015) (xy 157.258745 84.163555) (xy 157.261285 84.169895) (xy 157.262555 84.174965)
			(xy 157.266985 84.180665) (xy 157.269525 84.181935) (xy 157.272055 84.184465) (xy 157.274595 84.185735)
			(xy 157.277125 84.188265) (xy 157.286005 84.189535) (xy 157.323395 84.191435) (xy 157.331005 84.192705)
			(xy 157.349385 84.193345) (xy 157.353185 84.192075) (xy 157.358255 84.193345) (xy 157.548405 84.192075)
			(xy 157.550305 84.190175) (xy 157.551575 84.185105) (xy 157.550305 84.174965) (xy 157.549398 84.173695)
			(xy 157.722705 84.173695) (xy 157.723975 84.177495) (xy 157.725245 84.188905) (xy 157.728415 84.192075)
			(xy 157.737285 84.193345) (xy 158.450335 84.192705) (xy 158.467445 84.193345) (xy 158.471245 84.192075)
			(xy 158.483925 84.190805) (xy 158.520055 84.188905) (xy 158.529565 84.183195) (xy 158.532095 84.181935)
			(xy 158.536535 84.178765) (xy 158.537805 84.176225) (xy 158.660765 84.053265) (xy 158.662035 84.050735)
			(xy 158.669635 84.043125) (xy 158.672175 84.036785) (xy 158.676615 84.024745) (xy 158.678515 84.019035)
			(xy 158.679775 84.013965) (xy 158.681685 83.984175) (xy 158.683585 83.946785) (xy 158.684855 83.835235)
			(xy 158.684215 83.317395) (xy 158.684855 83.309155) (xy 158.683585 83.305355) (xy 158.684215 83.283175)
			(xy 158.682945 83.276835) (xy 158.680415 83.242605) (xy 158.679775 83.236905) (xy 158.681045 83.233095)
			(xy 158.679775 83.228025) (xy 158.673445 83.216615) (xy 158.667735 83.209645) (xy 158.660765 83.203945)
			(xy 158.659495 83.201405) (xy 158.653795 83.195705) (xy 158.651255 83.194435) (xy 158.648085 83.191265)
			(xy 158.646815 83.188735) (xy 158.641115 83.183025) (xy 158.638575 83.181755) (xy 158.636675 83.179855)
			(xy 158.635405 83.177325) (xy 158.629705 83.171615) (xy 158.627175 83.170355) (xy 158.624005 83.167185)
			(xy 158.622735 83.164645) (xy 158.617035 83.158945) (xy 158.614495 83.157675) (xy 158.612595 83.155775)
			(xy 158.611325 83.153235) (xy 158.605625 83.147535) (xy 158.603085 83.146265) (xy 158.599915 83.143095)
			(xy 158.598645 83.140565) (xy 158.592945 83.134855) (xy 158.590405 83.133585) (xy 158.587235 83.130415)
			(xy 158.585975 83.127885) (xy 158.580265 83.122175) (xy 158.577735 83.120915) (xy 158.575835 83.119005)
			(xy 158.574565 83.116475) (xy 158.568855 83.110775) (xy 158.566325 83.109505) (xy 158.563155 83.106335)
			(xy 158.561885 83.103795) (xy 158.556185 83.098095) (xy 158.553645 83.096825) (xy 158.551745 83.094925)
			(xy 158.550475 83.092395) (xy 158.544775 83.086685) (xy 158.542245 83.085415) (xy 158.539075 83.082245)
			(xy 158.537805 83.079715) (xy 158.532095 83.074005) (xy 158.529565 83.072745) (xy 158.523225 83.066405)
			(xy 158.520685 83.065135) (xy 158.511815 83.061335) (xy 158.503575 83.058165) (xy 158.497235 83.055625)
			(xy 158.489635 83.054355) (xy 158.486465 83.053725) (xy 158.482655 83.054995) (xy 158.478855 83.053725)
			(xy 158.443995 83.051825) (xy 158.388215 83.050555) (xy 157.846305 83.049925) (xy 157.842495 83.051195)
			(xy 157.823485 83.049925) (xy 157.819685 83.051195) (xy 157.798765 83.050555) (xy 157.791155 83.051825)
			(xy 157.773415 83.053095) (xy 157.768975 83.053725) (xy 157.767705 83.053725) (xy 157.753125 83.054355)
			(xy 157.746155 83.053725) (xy 157.742355 83.054995) (xy 157.739815 83.056265) (xy 157.736015 83.060065)
			(xy 157.733475 83.061335) (xy 157.731575 83.063235) (xy 157.730315 83.065765) (xy 157.727775 83.072105)
			(xy 157.725875 83.109505) (xy 157.724605 83.119645) (xy 157.723335 84.165455) (xy 157.722705 84.173695)
			(xy 157.549398 84.173695) (xy 157.543965 84.166085) (xy 157.541435 84.159745) (xy 157.538265 84.151505)
			(xy 157.536365 84.149605) (xy 157.535095 84.147075) (xy 157.530025 84.141995) (xy 157.528755 84.139465)
			(xy 157.523055 84.132495) (xy 157.518615 84.128055) (xy 157.514175 84.116015) (xy 157.511005 84.111575)
			(xy 157.507205 84.107775) (xy 157.505935 84.105245) (xy 157.500235 84.097005) (xy 157.498335 84.096365)
			(xy 157.497695 84.094465) (xy 157.495795 84.093835) (xy 157.494525 84.091295) (xy 157.491995 84.084955)
			(xy 157.488825 84.076715) (xy 157.486925 84.074815) (xy 157.485655 84.072275) (xy 157.483125 84.069745)
			(xy 157.477415 84.053905) (xy 157.470445 84.046925) (xy 157.469175 84.044395) (xy 157.460305 84.032985)
			(xy 157.457765 84.030445) (xy 157.455235 84.024115) (xy 157.453965 84.019035) (xy 157.445085 84.005095)
			(xy 157.440655 83.993055) (xy 157.437485 83.988615) (xy 157.434955 83.987345) (xy 157.433685 83.984815)
			(xy 157.431145 83.982275) (xy 157.427345 83.975935) (xy 157.421005 83.969605) (xy 157.416575 83.957555)
			(xy 157.410235 83.947415) (xy 157.407065 83.939175) (xy 157.404525 83.932845) (xy 157.398825 83.925865)
			(xy 157.395655 83.922695) (xy 157.391845 83.916365) (xy 157.385515 83.910025) (xy 157.382975 83.903685)
			(xy 157.379805 83.895445) (xy 157.376635 83.891005) (xy 157.371565 83.883405) (xy 157.369665 83.876435)
			(xy 157.367135 83.870095) (xy 157.361425 83.859315) (xy 157.358895 83.850445) (xy 157.360155 83.825085)
			(xy 157.366495 83.816215) (xy 157.369035 83.813685) (xy 157.372835 83.807345) (xy 157.376005 83.804175)
			(xy 157.377905 83.803535) (xy 157.378535 83.802905) (xy 157.381705 83.799735) (xy 157.382975 83.797205)
			(xy 157.388685 83.791495) (xy 157.391215 83.790235) (xy 157.394385 83.787065) (xy 157.395655 83.784525)
			(xy 157.401355 83.778825) (xy 157.403895 83.777555) (xy 157.405795 83.775655) (xy 157.407065 83.773115)
			(xy 157.412765 83.767415) (xy 157.415305 83.766145) (xy 157.418475 83.762975) (xy 157.419735 83.760435)
			(xy 157.425445 83.754735) (xy 157.427975 83.753465) (xy 157.429875 83.751565) (xy 157.431145 83.749035)
			(xy 157.436845 83.743325) (xy 157.439385 83.742055) (xy 157.442555 83.738885) (xy 157.443825 83.736355)
			(xy 157.449525 83.730645) (xy 157.452065 83.729385) (xy 157.455235 83.726215) (xy 157.456495 83.723675)
			(xy 157.462205 83.717975) (xy 157.464735 83.716705) (xy 157.466645 83.714805) (xy 157.467905 83.712265)
			(xy 157.473615 83.706565) (xy 157.476145 83.705295) (xy 157.479315 83.702125) (xy 157.480585 83.699595)
			(xy 157.486295 83.693895) (xy 157.488825 83.692625) (xy 157.491995 83.689455) (xy 157.493265 83.686915)
			(xy 157.497695 83.682485) (xy 157.500235 83.681215) (xy 157.504675 83.676775) (xy 157.505935 83.674245)
			(xy 157.511645 83.667265) (xy 157.513545 83.665365) (xy 157.516085 83.659025) (xy 157.517345 83.653955)
			(xy 157.522415 83.642545) (xy 157.523685 83.637475) (xy 157.525585 83.607685) (xy 157.527485 83.570295)
			(xy 157.528125 83.521485) (xy 157.527485 83.520855) (xy 157.528755 83.517055) (xy 157.528125 83.357965)
			(xy 157.528755 83.348455) (xy 157.527485 83.344655) (xy 157.526215 83.271135) (xy 157.524955 83.267325)
			(xy 157.523055 83.237535) (xy 157.517345 83.224225) (xy 157.514175 83.215985) (xy 157.509745 83.209015)
			(xy 157.505935 83.205215) (xy 157.504675 83.202675) (xy 157.497695 83.195705) (xy 157.495165 83.194435)
			(xy 157.493265 83.192535) (xy 157.491995 83.190005) (xy 157.485025 83.183025) (xy 157.482485 83.181755)
			(xy 157.480585 83.179855) (xy 157.479315 83.177325) (xy 157.459665 83.157675) (xy 157.457765 83.157045)
			(xy 157.456495 83.154505) (xy 157.448255 83.146265) (xy 157.445725 83.144995) (xy 157.442555 83.140565)
			(xy 157.436845 83.134855) (xy 157.434315 83.133585) (xy 157.432415 83.131685) (xy 157.431145 83.129155)
			(xy 157.424175 83.122175) (xy 157.421645 83.120915) (xy 157.419735 83.119005) (xy 157.418475 83.116475)
			(xy 157.400085 83.098095) (xy 157.397555 83.096825) (xy 157.395655 83.094925) (xy 157.394385 83.092395)
			(xy 157.387415 83.085415) (xy 157.384875 83.084155) (xy 157.378535 83.076545) (xy 157.376005 83.074005)
			(xy 157.373465 83.072745) (xy 157.367135 83.066405) (xy 157.364595 83.065135) (xy 157.355725 83.061335)
			(xy 157.347485 83.058165) (xy 157.341145 83.055625) (xy 157.333535 83.054355) (xy 157.305655 83.053095)
			(xy 157.268255 83.051195) (xy 157.164305 83.049925) (xy 156.574855 83.051195) (xy 156.569145 83.055625)
			(xy 156.567885 83.060695) (xy 156.24183 83.060695) (xy 156.233855 83.054995) (xy 156.228785 83.053725)
			(xy 156.211035 83.052455) (xy 156.207235 83.051195) (xy 156.190755 83.049925) (xy 156.186955 83.051195)
			(xy 156.177445 83.053095) (xy 156.160965 83.054355) (xy 156.156525 83.056265) (xy 156.153995 83.058795)
			(xy 156.151455 83.060065) (xy 156.142585 83.066405) (xy 156.136245 83.074005) (xy 156.130545 83.078445)
			(xy 156.129275 83.080985) (xy 156.122305 83.087955) (xy 156.119765 83.089225) (xy 156.117865 83.091125)
			(xy 156.116595 83.093655) (xy 156.110895 83.099365) (xy 156.108355 83.100625) (xy 156.105185 83.103795)
			(xy 156.103925 83.106335) (xy 156.098215 83.112035) (xy 156.095685 83.113305) (xy 156.093785 83.115205)
			(xy 156.092515 83.117745) (xy 156.085535 83.124715) (xy 156.083005 83.125985) (xy 156.081105 83.127885)
			(xy 156.079835 83.130415) (xy 156.074135 83.136125) (xy 156.071595 83.137395) (xy 156.069695 83.139295)
			(xy 156.068425 83.141825) (xy 156.061455 83.148805) (xy 156.058915 83.150065) (xy 156.057015 83.151975)
			(xy 156.055755 83.154505) (xy 156.050045 83.160205) (xy 156.047515 83.161475) (xy 156.044345 83.164645)
			(xy 156.043075 83.167185) (xy 156.037375 83.172885) (xy 156.034835 83.174155) (xy 156.032935 83.176055)
			(xy 156.031665 83.178595) (xy 156.024695 83.185565) (xy 156.022155 83.186835) (xy 156.020255 83.188735)
			(xy 156.018985 83.191265) (xy 156.013285 83.196975) (xy 156.010745 83.198245) (xy 156.008845 83.200145)
			(xy 156.007575 83.202675) (xy 156.000605 83.209645) (xy 155.998075 83.210915) (xy 155.996165 83.212815)
			(xy 155.994905 83.215355) (xy 155.989195 83.221055) (xy 155.986665 83.222325) (xy 155.983495 83.225495)
			(xy 155.982225 83.228025) (xy 155.976525 83.233735) (xy 155.973985 83.234995) (xy 155.972085 83.236905)
			(xy 155.970815 83.239435) (xy 155.963845 83.246405) (xy 155.961315 83.247675) (xy 155.959415 83.249575)
			(xy 155.958145 83.252115) (xy 155.951165 83.259085) (xy 155.948635 83.260355) (xy 155.939125 83.273665)
			(xy 155.942295 83.279365) (xy 155.951165 83.280635) (xy 155.960675 83.281265) (xy 156.006945 83.280635)
			(xy 156.010745 83.281905) (xy 156.027225 83.280635) (xy 156.074765 83.282535) (xy 156.084905 83.281265)
			(xy 156.088075 83.280635) (xy 156.091875 83.281905) (xy 156.104555 83.283175) (xy 156.133075 83.285075)
			(xy 156.140055 83.289505) (xy 156.148295 83.297745) (xy 156.149555 83.302815) (xy 156.151455 83.337685)
			(xy 156.152725 83.342745) (xy 156.153365 83.354795) (xy 156.152095 83.358595) (xy 156.153365 83.381415)
			(xy 156.152095 83.385215) (xy 156.153365 83.394095) (xy 156.152725 83.508815) (xy 156.153365 83.524655)
			(xy 156.152095 83.528465) (xy 156.153365 83.548745) (xy 156.150825 83.555085) (xy 156.148925 83.591205)
			(xy 156.142585 83.601355) (xy 156.137515 83.608955) (xy 156.134975 83.610225) (xy 156.124835 83.616565)
			(xy 156.115965 83.619095) (xy 156.108995 83.618465) (xy 156.086175 83.619735) (xy 156.081105 83.621005)
			(xy 156.066525 83.621635) (xy 156.062725 83.620365) (xy 156.050045 83.621635) (xy 155.790815 83.621005)
			(xy 155.774965 83.621635) (xy 155.768625 83.619095) (xy 155.745175 83.618465) (xy 155.738205 83.619095)
			(xy 155.734405 83.617835) (xy 155.731865 83.616565) (xy 155.724265 83.611495) (xy 155.721725 83.610225)
			(xy 155.716025 83.605785) (xy 155.714755 83.603255) (xy 155.708415 83.594375) (xy 155.704615 83.585505)
			(xy 155.703345 83.561415) (xy 155.702075 83.546205) (xy 155.697645 83.541775) (xy 155.692565 83.543035)
			(xy 155.690035 83.545575) (xy 155.687505 83.546845) (xy 155.672285 83.562055) (xy 155.669755 83.563325)
			(xy 155.667855 83.565225) (xy 155.666585 83.567755) (xy 155.659615 83.574735) (xy 155.657075 83.575995)
			(xy 155.650735 83.583605) (xy 155.645665 83.588675) (xy 155.643125 83.589945) (xy 155.639965 83.594375)
			(xy 155.635525 83.598815) (xy 155.632995 83.600085) (xy 155.629825 83.604515) (xy 155.624115 83.610225)
			(xy 155.621585 83.611495) (xy 155.619685 83.613395) (xy 155.618415 83.615925) (xy 155.611445 83.622905)
			(xy 155.608905 83.624165) (xy 155.607005 83.626075) (xy 155.605735 83.628605) (xy 155.598765 83.635575)
			(xy 155.596865 83.636215) (xy 155.595595 83.638745) (xy 155.587355 83.646985) (xy 155.584815 83.648255)
			(xy 155.581645 83.651425) (xy 155.580385 83.653955) (xy 155.573405 83.660925) (xy 155.571505 83.661565)
			(xy 155.570245 83.664095) (xy 155.562005 83.672335) (xy 155.559465 83.673605) (xy 155.556295 83.678045)
			(xy 155.550595 83.683745) (xy 155.548055 83.685015) (xy 155.546155 83.686915) (xy 155.544895 83.689455)
			(xy 155.537915 83.696425) (xy 155.535385 83.697695) (xy 155.533485 83.699595) (xy 155.532215 83.702125)
			(xy 155.523975 83.710365) (xy 155.522075 83.711005) (xy 155.520805 83.713535) (xy 155.512565 83.721775)
			(xy 155.510025 83.723045) (xy 155.506865 83.727485) (xy 155.502425 83.731915) (xy 155.499885 83.733185)
			(xy 155.497985 83.735085) (xy 155.496715 83.737625) (xy 155.489745 83.744595) (xy 155.487215 83.745865)
			(xy 155.485305 83.747765) (xy 155.484045 83.750295) (xy 155.477065 83.757275) (xy 155.474535 83.758535)
			(xy 155.471365 83.762975) (xy 155.464395 83.769945) (xy 155.461855 83.771215) (xy 155.459955 83.773115)
			(xy 155.451085 83.792135) (xy 155.452355 83.802275) (xy 155.451085 83.806075) (xy 155.449185 83.835865)
			(xy 155.447915 83.843475) (xy 155.447285 83.850445) (xy 154.669037 83.850445) (xy 154.669306 83.619735)
			(xy 155.179805 83.619735) (xy 155.181075 83.623535) (xy 155.182345 83.684385) (xy 155.183615 83.688185)
			(xy 155.184875 83.713535) (xy 155.189945 83.724945) (xy 155.191215 83.730015) (xy 155.197555 83.741425)
			(xy 155.202625 83.746495) (xy 155.203895 83.749035) (xy 155.208335 83.754735) (xy 155.210865 83.756005)
			(xy 155.217835 83.762975) (xy 155.218465 83.764875) (xy 155.221005 83.766145) (xy 155.226075 83.771215)
			(xy 155.228615 83.772485) (xy 155.231145 83.775015) (xy 155.236215 83.776285) (xy 155.238755 83.773755)
			(xy 155.241285 83.772485) (xy 155.245095 83.768675) (xy 155.247625 83.767415) (xy 155.252065 83.762975)
			(xy 155.253335 83.760435) (xy 155.257765 83.756005) (xy 155.260305 83.754735) (xy 155.264745 83.750295)
			(xy 155.266005 83.747765) (xy 155.270445 83.743325) (xy 155.272975 83.742055) (xy 155.277415 83.737625)
			(xy 155.278685 83.735085) (xy 155.281855 83.731915) (xy 155.284385 83.730645) (xy 155.288825 83.726215)
			(xy 155.290095 83.723675) (xy 155.294535 83.719235) (xy 155.297065 83.717975) (xy 155.301505 83.713535)
			(xy 155.302765 83.711005) (xy 155.307205 83.706565) (xy 155.309745 83.705295) (xy 155.312905 83.702125)
			(xy 155.314175 83.699595) (xy 155.318615 83.695155) (xy 155.321145 83.693895) (xy 155.325585 83.689455)
			(xy 155.326855 83.686915) (xy 155.331285 83.682485) (xy 155.333825 83.681215) (xy 155.338265 83.676775)
			(xy 155.339525 83.674245) (xy 155.342695 83.671075) (xy 155.345235 83.669805) (xy 155.352205 83.664095)
			(xy 155.355375 83.660925) (xy 155.361715 83.658395) (xy 155.369955 83.655225) (xy 155.376925 83.648255)
			(xy 155.379465 83.646985) (xy 155.386435 83.641275) (xy 155.387705 83.638745) (xy 155.394675 83.631775)
			(xy 155.397205 83.630505) (xy 155.400375 83.626075) (xy 155.406085 83.620365) (xy 155.408615 83.619095)
			(xy 155.410515 83.617195) (xy 155.411785 83.614665) (xy 155.417495 83.608955) (xy 155.420025 83.607685)
			(xy 155.421925 83.605785) (xy 155.423195 83.603255) (xy 155.430165 83.596275) (xy 155.432705 83.595015)
			(xy 155.434605 83.593115) (xy 155.435875 83.590575) (xy 155.441575 83.584865) (xy 155.444115 83.583605)
			(xy 155.446015 83.581705) (xy 155.447285 83.579165) (xy 155.454255 83.572195) (xy 155.456785 83.570925)
			(xy 155.459955 83.566495) (xy 155.466925 83.559515) (xy 155.468835 83.558885) (xy 155.470095 83.556345)
			(xy 155.478335 83.548105) (xy 155.480875 83.546845) (xy 155.482775 83.544935) (xy 155.484045 83.542405)
			(xy 155.491015 83.535435) (xy 155.493545 83.534165) (xy 155.495455 83.532265) (xy 155.496715 83.529725)
			(xy 155.503695 83.522755) (xy 155.506225 83.521485) (xy 155.512565 83.513885) (xy 155.516365 83.510085)
			(xy 155.518905 83.508815) (xy 155.525245 83.501205) (xy 155.527775 83.498675) (xy 155.529675 83.498035)
			(xy 155.530945 83.495505) (xy 155.539185 83.487265) (xy 155.541725 83.485995) (xy 155.543625 83.484095)
			(xy 155.544895 83.481555) (xy 155.551865 83.474585) (xy 155.554395 83.473315) (xy 155.556295 83.471415)
			(xy 155.557565 83.468875) (xy 155.564535 83.461905) (xy 155.567075 83.460635) (xy 155.570245 83.456205)
			(xy 155.577215 83.449235) (xy 155.579745 83.447965) (xy 155.582915 83.443525) (xy 155.588625 83.437825)
			(xy 155.590525 83.437195) (xy 155.591795 83.434655) (xy 155.600035 83.426415) (xy 155.602565 83.425145)
			(xy 155.604465 83.423245) (xy 155.605735 83.420715) (xy 155.612705 83.413735) (xy 155.615245 83.412475)
			(xy 155.617145 83.410565) (xy 155.618415 83.408035) (xy 155.625385 83.401065) (xy 155.627925 83.399795)
			(xy 155.631085 83.395355) (xy 155.636795 83.389655) (xy 155.639325 83.388385) (xy 155.641225 83.386485)
			(xy 155.642495 83.383945) (xy 155.649465 83.376975) (xy 155.652005 83.375705) (xy 155.658345 83.368105)
			(xy 155.660875 83.365565) (xy 155.663415 83.364305) (xy 155.665315 83.362395) (xy 155.666585 83.359865)
			(xy 155.673555 83.352895) (xy 155.676095 83.351625) (xy 155.677995 83.349725) (xy 155.679265 83.347185)
			(xy 155.686235 83.340215) (xy 155.688765 83.338945) (xy 155.691935 83.334515) (xy 155.697645 83.328805)
			(xy 155.700175 83.327535) (xy 155.702075 83.325635) (xy 155.703345 83.323105) (xy 155.710315 83.316125)
			(xy 155.712855 83.314865) (xy 155.716025 83.310425) (xy 155.721725 83.304725) (xy 155.724265 83.303455)
			(xy 155.726165 83.301555) (xy 155.727425 83.299015) (xy 155.733135 83.293315) (xy 155.735665 83.292045)
			(xy 155.738835 83.288875) (xy 155.740105 83.286345) (xy 155.747075 83.279365) (xy 155.748985 83.278735)
			(xy 155.750245 83.276205) (xy 155.758485 83.267965) (xy 155.761025 83.266695) (xy 155.762925 83.264795)
			(xy 155.764195 83.262255) (xy 155.769895 83.256555) (xy 155.772435 83.255285) (xy 155.774335 83.253385)
			(xy 155.775605 83.250845) (xy 155.782575 83.243875) (xy 155.785105 83.242605) (xy 155.787015 83.240705)
			(xy 155.788275 83.238165) (xy 155.793985 83.232465) (xy 155.796515 83.231195) (xy 155.799685 83.228025)
			(xy 155.800955 83.225495) (xy 155.807925 83.218525) (xy 155.810465 83.217255) (xy 155.812365 83.215355)
			(xy 155.813625 83.212815) (xy 155.820605 83.205845) (xy 155.822505 83.205215) (xy 155.823765 83.202675)
			(xy 155.830745 83.195705) (xy 155.833275 83.194435) (xy 155.835175 83.192535) (xy 155.836445 83.190005)
			(xy 155.843415 83.183025) (xy 155.845955 83.181755) (xy 155.847855 83.179855) (xy 155.849125 83.177325)
			(xy 155.856095 83.170355) (xy 155.858635 83.169085) (xy 155.860535 83.167185) (xy 155.861805 83.164645)
			(xy 155.867505 83.158945) (xy 155.870035 83.157675) (xy 155.871945 83.155775) (xy 155.873205 83.153235)
			(xy 155.880185 83.146265) (xy 155.882715 83.144995) (xy 155.884615 83.143095) (xy 155.885885 83.140565)
			(xy 155.892855 83.133585) (xy 155.895395 83.132325) (xy 155.898565 83.127885) (xy 155.904265 83.122175)
			(xy 155.906805 83.120915) (xy 155.908705 83.119005) (xy 155.909975 83.116475) (xy 155.916945 83.109505)
			(xy 155.919475 83.108235) (xy 155.921385 83.106335) (xy 155.922645 83.103795) (xy 155.928355 83.098095)
			(xy 155.930885 83.096825) (xy 155.932785 83.094925) (xy 155.934055 83.092395) (xy 155.941025 83.085415)
			(xy 155.943565 83.084155) (xy 155.945465 83.082245) (xy 155.946735 83.079715) (xy 155.953705 83.072745)
			(xy 155.956245 83.071475) (xy 155.962575 83.063865) (xy 155.965115 83.061335) (xy 155.967655 83.060065)
			(xy 155.969555 83.058165) (xy 155.970815 83.055625) (xy 155.977795 83.048655) (xy 155.980325 83.047385)
			(xy 155.982225 83.045485) (xy 155.983495 83.042955) (xy 155.989195 83.035985) (xy 155.992365 83.032815)
			(xy 155.994905 83.026475) (xy 155.998075 83.018235) (xy 156.003145 83.010625) (xy 156.006315 83.003655)
			(xy 156.008845 82.997315) (xy 156.012015 82.989075) (xy 156.015185 82.978305) (xy 156.017085 82.940905)
			(xy 156.018355 82.906685) (xy 156.018985 82.895905) (xy 156.018985 82.894635) (xy 156.018873 82.620825)
			(xy 156.190125 82.620825) (xy 156.191385 82.624625) (xy 156.192655 82.676605) (xy 156.193925 82.680405)
			(xy 156.195195 82.705755) (xy 156.200265 82.717165) (xy 156.202165 82.725405) (xy 156.204065 82.737455)
			(xy 156.210405 82.747595) (xy 156.212935 82.753925) (xy 156.216745 82.764075) (xy 156.222445 82.771045)
			(xy 156.225615 82.774215) (xy 156.226885 82.776745) (xy 156.233855 82.783715) (xy 156.236395 82.784985)
			(xy 156.242725 82.791325) (xy 156.249065 82.793855) (xy 156.257305 82.797025) (xy 156.261745 82.800195)
			(xy 156.264915 82.804635) (xy 156.268085 82.807805) (xy 156.270615 82.809075) (xy 156.272515 82.810975)
			(xy 156.275055 82.817315) (xy 156.276955 82.824285) (xy 156.278855 82.826185) (xy 156.280125 82.828725)
			(xy 156.283295 82.831885) (xy 156.285825 82.833155) (xy 156.288995 82.837595) (xy 156.292165 82.840765)
			(xy 156.308015 82.846465) (xy 156.310545 82.849005) (xy 156.311815 82.851535) (xy 156.316255 82.855975)
			(xy 156.318785 82.857245) (xy 156.320685 82.859145) (xy 156.323225 82.865475) (xy 156.326395 82.873715)
			(xy 156.329565 82.878155) (xy 156.333995 82.881325) (xy 156.335905 82.883225) (xy 156.337165 82.885765)
			(xy 156.340335 82.888935) (xy 156.346675 82.891465) (xy 156.358715 82.895905) (xy 156.366955 82.899075)
			(xy 156.383435 82.900345) (xy 156.415765 82.902245) (xy 156.469005 82.903515) (xy 156.825845 82.904145)
			(xy 156.827115 82.904145) (xy 157.060365 82.902875) (xy 157.063535 82.899705) (xy 157.066065 82.889565)
			(xy 157.064795 82.679135) (xy 157.060365 82.674705) (xy 157.055295 82.673435) (xy 156.609715 82.672805)
			(xy 156.593865 82.673435) (xy 156.590065 82.672165) (xy 156.569145 82.672805) (xy 156.554565 82.672165)
			(xy 156.550765 82.673435) (xy 156.538725 82.671535) (xy 156.535555 82.670895) (xy 156.531755 82.672165)
			(xy 156.521615 82.673435) (xy 156.517805 82.672165) (xy 156.507665 82.669635) (xy 156.474705 82.668365)
			(xy 156.462665 82.656325) (xy 156.461395 82.651245) (xy 156.460135 82.642375) (xy 156.458865 82.613225)
			(xy 156.457595 82.609415) (xy 156.458865 82.587865) (xy 156.457595 82.584065) (xy 156.458225 82.503565)
			(xy 156.457595 82.490255) (xy 156.458865 82.486455) (xy 156.460135 82.477585) (xy 156.461395 82.449695)
			(xy 156.467735 82.440815) (xy 156.473435 82.435115) (xy 156.483585 82.432585) (xy 156.515275 82.431315)
			(xy 156.519075 82.430045) (xy 156.539995 82.430685) (xy 156.967185 82.429415) (xy 156.974795 82.428145)
			(xy 156.978595 82.424345) (xy 156.981135 82.415465) (xy 156.980495 82.322295) (xy 156.981135 82.310255)
			(xy 156.979865 82.306455) (xy 156.978595 82.289965) (xy 156.977325 82.277295) (xy 156.976695 82.262715)
			(xy 156.977325 82.258285) (xy 156.976065 82.254475) (xy 156.972255 82.248135) (xy 156.965285 82.241165)
			(xy 156.956415 82.238635) (xy 156.914585 82.237365) (xy 156.910775 82.236095) (xy 156.901905 82.234825)
			(xy 156.885425 82.236095) (xy 156.876555 82.234825) (xy 156.860705 82.235465) (xy 156.465205 82.234195)
			(xy 156.460765 82.232295) (xy 156.457595 82.225325) (xy 156.458225 82.092845) (xy 156.457595 82.078275)
			(xy 156.458865 82.074475) (xy 156.458225 82.053555) (xy 156.459495 82.047215) (xy 156.460765 82.025665)
			(xy 156.462035 82.009185) (xy 156.463935 82.007285) (xy 156.465205 82.004745) (xy 156.472175 81.997775)
			(xy 156.474705 81.996515) (xy 156.478515 81.995245) (xy 156.513375 81.993345) (xy 156.518445 81.992075)
			(xy 156.530485 81.991445) (xy 156.534285 81.992705) (xy 156.557105 81.991445) (xy 156.560905 81.992705)
			(xy 156.573585 81.991445) (xy 157.059095 81.990175) (xy 157.063535 81.987005) (xy 157.066065 81.978125)
			(xy 157.065435 81.873545) (xy 157.066065 81.858965) (xy 157.064795 81.855165) (xy 157.066065 81.833615)
			(xy 157.064795 81.829815) (xy 157.063535 81.824745) (xy 157.061625 81.781005) (xy 157.059725 81.776575)
			(xy 157.057195 81.774035) (xy 157.055925 81.771505) (xy 157.054025 81.769605) (xy 157.051485 81.768335)
			(xy 157.048955 81.765795) (xy 157.043885 81.764535) (xy 157.001415 81.762625) (xy 156.995075 81.761365)
			(xy 156.979235 81.760725) (xy 156.975425 81.761995) (xy 156.962755 81.760725) (xy 156.422735 81.761995)
			(xy 156.418925 81.763265) (xy 156.380265 81.765165) (xy 156.370125 81.768965) (xy 156.356185 81.774035)
			(xy 156.351745 81.777205) (xy 156.349215 81.779745) (xy 156.346675 81.781005) (xy 156.344145 81.783545)
			(xy 156.341605 81.784815) (xy 156.335905 81.790515) (xy 156.334635 81.793055) (xy 156.331465 81.796225)
			(xy 156.328925 81.797485) (xy 156.321955 81.804465) (xy 156.320685 81.806995) (xy 156.318785 81.808895)
			(xy 156.316255 81.810165) (xy 156.310545 81.815875) (xy 156.309285 81.818405) (xy 156.307375 81.820305)
			(xy 156.304845 81.821575) (xy 156.297875 81.828545) (xy 156.296605 81.831085) (xy 156.292165 81.834255)
			(xy 156.286465 81.839955) (xy 156.285195 81.842485) (xy 156.283295 81.844395) (xy 156.280755 81.845655)
			(xy 156.275055 81.851365) (xy 156.273785 81.853895) (xy 156.270615 81.857065) (xy 156.268085 81.858335)
			(xy 156.261105 81.865305) (xy 156.259845 81.867845) (xy 156.257935 81.869745) (xy 156.255405 81.871015)
			(xy 156.249695 81.876715) (xy 156.248435 81.879255) (xy 156.246525 81.881155) (xy 156.243995 81.882425)
			(xy 156.238295 81.888125) (xy 156.237025 81.890665) (xy 156.233855 81.893835) (xy 156.231315 81.895095)
			(xy 156.225615 81.900805) (xy 156.224345 81.903335) (xy 156.222445 81.905235) (xy 156.219915 81.906505)
			(xy 156.214205 81.912215) (xy 156.212935 81.914745) (xy 156.205335 81.926155) (xy 156.202795 81.936295)
			(xy 156.201535 81.952775) (xy 156.200265 81.956585) (xy 156.198995 81.961645) (xy 156.196455 81.967985)
			(xy 156.195195 81.973055) (xy 156.193925 81.985735) (xy 156.192025 82.018065) (xy 156.190755 82.056095)
			(xy 156.190125 82.620825) (xy 156.018873 82.620825) (xy 156.018355 81.351275) (xy 156.018985 81.332895)
			(xy 156.017725 81.329095) (xy 156.016455 81.320215) (xy 156.014555 81.280295) (xy 156.008845 81.270785)
			(xy 156.007575 81.268245) (xy 156.003145 81.262545) (xy 156.000605 81.261275) (xy 155.994905 81.255565)
			(xy 155.993635 81.253035) (xy 155.991735 81.251135) (xy 155.989195 81.249865) (xy 155.980965 81.241625)
			(xy 155.979695 81.239095) (xy 155.975255 81.235925) (xy 155.969555 81.230215) (xy 155.968285 81.227685)
			(xy 155.966385 81.225785) (xy 155.963845 81.224515) (xy 155.956875 81.217545) (xy 155.955605 81.215005)
			(xy 155.951165 81.211835) (xy 155.945465 81.206135) (xy 155.944195 81.203595) (xy 155.942295 81.201695)
			(xy 155.939765 81.200425) (xy 155.932785 81.193455) (xy 155.931525 81.190925) (xy 155.923915 81.184585)
			(xy 155.920115 81.180775) (xy 155.918845 81.178245) (xy 155.911235 81.171905) (xy 155.908705 81.169375)
			(xy 155.907435 81.166835) (xy 155.905535 81.164935) (xy 155.902995 81.163665) (xy 155.896025 81.156695)
			(xy 155.894765 81.154155) (xy 155.890325 81.150985) (xy 155.884615 81.145285) (xy 155.883355 81.142755)
			(xy 155.881445 81.140845) (xy 155.878915 81.139585) (xy 155.871945 81.132605) (xy 155.870675 81.130075)
			(xy 155.868775 81.128175) (xy 155.866235 81.126905) (xy 155.859265 81.121195) (xy 155.857365 81.119305)
			(xy 155.854825 81.118035) (xy 155.848495 81.115495) (xy 155.836445 81.111065) (xy 155.829475 81.107895)
			(xy 155.821235 81.105985) (xy 155.814895 81.104725) (xy 155.799685 81.103455) (xy 155.776235 81.102815)
			(xy 155.772435 81.104085) (xy 155.766095 81.107895) (xy 155.764195 81.114865) (xy 155.763555 82.802735)
			(xy 155.764195 82.818575) (xy 155.762925 82.822385) (xy 155.764195 82.841395) (xy 155.762925 82.845205)
			(xy 155.764195 82.866745) (xy 155.761655 82.873085) (xy 155.761025 82.881325) (xy 155.761655 82.888295)
			(xy 155.760385 82.892105) (xy 155.759125 82.911115) (xy 155.752785 82.919985) (xy 155.748985 82.926325)
			(xy 155.747075 82.928235) (xy 155.744545 82.929495) (xy 155.738835 82.935205) (xy 155.737575 82.937735)
			(xy 155.735665 82.939635) (xy 155.733135 82.940905) (xy 155.727425 82.946605) (xy 155.726165 82.949145)
			(xy 155.722995 82.952315) (xy 155.720455 82.953585) (xy 155.714755 82.959285) (xy 155.713485 82.961825)
			(xy 155.710315 82.964995) (xy 155.707785 82.966255) (xy 155.703345 82.970695) (xy 155.702075 82.973235)
			(xy 155.698905 82.976405) (xy 155.696375 82.977665) (xy 155.690665 82.983375) (xy 155.689405 82.985905)
			(xy 155.686235 82.989075) (xy 155.683695 82.990345) (xy 155.677995 82.996045) (xy 155.676725 82.998585)
			(xy 155.673555 83.001755) (xy 155.667215 83.005555) (xy 155.660875 83.011895) (xy 155.652005 83.014435)
			(xy 155.645665 83.018235) (xy 155.640595 83.023305) (xy 155.638065 83.024575) (xy 155.631085 83.030275)
			(xy 155.625385 83.037245) (xy 155.618415 83.042955) (xy 155.617145 83.045485) (xy 155.611445 83.051195)
			(xy 155.608905 83.052455) (xy 155.605735 83.055625) (xy 155.604465 83.058165) (xy 155.600035 83.062605)
			(xy 155.597495 83.063865) (xy 155.594325 83.067035) (xy 155.593055 83.069575) (xy 155.587355 83.075275)
			(xy 155.584815 83.076545) (xy 155.581645 83.079715) (xy 155.580385 83.082245) (xy 155.575945 83.086685)
			(xy 155.573405 83.087955) (xy 155.570245 83.091125) (xy 155.568975 83.093655) (xy 155.563265 83.099365)
			(xy 155.560735 83.100625) (xy 155.557565 83.103795) (xy 155.556295 83.106335) (xy 155.551865 83.110775)
			(xy 155.549325 83.112035) (xy 155.546155 83.115205) (xy 155.544895 83.117745) (xy 155.539185 83.123445)
			(xy 155.536655 83.124715) (xy 155.533485 83.127885) (xy 155.532215 83.130415) (xy 155.527775 83.134855)
			(xy 155.525245 83.136125) (xy 155.520805 83.140565) (xy 155.519535 83.143095) (xy 155.515095 83.147535)
			(xy 155.512565 83.148805) (xy 155.509395 83.151975) (xy 155.508125 83.154505) (xy 155.502425 83.160205)
			(xy 155.499885 83.161475) (xy 155.496715 83.164645) (xy 155.495455 83.167185) (xy 155.489745 83.172885)
			(xy 155.487215 83.174155) (xy 155.484045 83.177325) (xy 155.482775 83.179855) (xy 155.478335 83.184295)
			(xy 155.475805 83.185565) (xy 155.472635 83.188735) (xy 155.471365 83.191265) (xy 155.466925 83.195705)
			(xy 155.464395 83.196975) (xy 155.459955 83.201405) (xy 155.458685 83.203945) (xy 155.454255 83.208375)
			(xy 155.451715 83.209645) (xy 155.448545 83.212815) (xy 155.447285 83.215355) (xy 155.441575 83.221055)
			(xy 155.439045 83.222325) (xy 155.435875 83.225495) (xy 155.434605 83.228025) (xy 155.428895 83.233735)
			(xy 155.426365 83.234995) (xy 155.424465 83.236905) (xy 155.423195 83.239435) (xy 155.417495 83.245145)
			(xy 155.414955 83.246405) (xy 155.410515 83.250845) (xy 155.409255 83.253385) (xy 155.406085 83.256555)
			(xy 155.403545 83.257815) (xy 155.399105 83.262255) (xy 155.397845 83.264795) (xy 155.393405 83.269225)
			(xy 155.390865 83.270495) (xy 155.387705 83.273665) (xy 155.386435 83.276205) (xy 155.380735 83.281905)
			(xy 155.378195 83.283175) (xy 155.375025 83.286345) (xy 155.373755 83.288875) (xy 155.368055 83.294575)
			(xy 155.365515 83.295845) (xy 155.363615 83.297745) (xy 155.362345 83.300285) (xy 155.356645 83.305985)
			(xy 155.354105 83.307255) (xy 155.349675 83.311695) (xy 155.348405 83.314225) (xy 155.345235 83.317395)
			(xy 155.342695 83.318665) (xy 155.338265 83.323105) (xy 155.336995 83.325635) (xy 155.332555 83.330075)
			(xy 155.330025 83.331345) (xy 155.326855 83.334515) (xy 155.325585 83.337045) (xy 155.319885 83.342745)
			(xy 155.317345 83.344015) (xy 155.314175 83.347185) (xy 155.312905 83.349725) (xy 155.308475 83.354155)
			(xy 155.305935 83.355425) (xy 155.301505 83.359865) (xy 155.300235 83.362395) (xy 155.295795 83.366835)
			(xy 155.293265 83.368105) (xy 155.290095 83.371275) (xy 155.288825 83.373805) (xy 155.283125 83.379515)
			(xy 155.280585 83.380775) (xy 155.278685 83.382685) (xy 155.277415 83.385215) (xy 155.271715 83.390925)
			(xy 155.269175 83.392185) (xy 155.266005 83.395355) (xy 155.264745 83.397895) (xy 155.259035 83.403595)
			(xy 155.256505 83.404865) (xy 155.253335 83.408035) (xy 155.252065 83.410565) (xy 155.246355 83.416275)
			(xy 155.243825 83.417545) (xy 155.241925 83.419445) (xy 155.240655 83.421975) (xy 155.234945 83.427685)
			(xy 155.232415 83.428955) (xy 155.229245 83.432125) (xy 155.227975 83.434655) (xy 155.222275 83.440365)
			(xy 155.219735 83.441625) (xy 155.216565 83.444795) (xy 155.215295 83.447335) (xy 155.209595 83.453035)
			(xy 155.207065 83.454305) (xy 155.205165 83.456205) (xy 155.203895 83.458745) (xy 155.201355 83.461275)
			(xy 155.200095 83.463805) (xy 155.195025 83.468875) (xy 155.193755 83.471415) (xy 155.191215 83.477755)
			(xy 155.189945 83.482825) (xy 155.184875 83.494235) (xy 155.183615 83.506915) (xy 155.181705 83.544305)
			(xy 155.180445 83.587405) (xy 155.179805 83.619735) (xy 154.669306 83.619735) (xy 154.669585 83.380775)
			(xy 154.668945 83.366205) (xy 154.670215 83.362395) (xy 154.671485 83.357325) (xy 154.672745 83.324375)
			(xy 154.678455 83.317395) (xy 154.684795 83.311055) (xy 154.694935 83.308525) (xy 154.727895 83.307255)
			(xy 154.731695 83.305985) (xy 154.752615 83.306625) (xy 155.094875 83.305355) (xy 155.169665 83.304085)
			(xy 155.222905 83.300285) (xy 155.227975 83.299015) (xy 155.238755 83.295845) (xy 155.243825 83.294575)
			(xy 155.256505 83.293315) (xy 155.271715 83.292045) (xy 155.274885 83.288875) (xy 155.277415 83.278735)
			(xy 155.276785 83.162745) (xy 155.277415 83.150705) (xy 155.276145 83.146895) (xy 155.276785 83.124715)
			(xy 155.275515 83.118375) (xy 155.272975 83.082885) (xy 155.272345 83.078445) (xy 155.273615 83.074645)
			(xy 155.272345 83.069575) (xy 155.271075 83.067035) (xy 155.265375 83.060065) (xy 155.261575 83.056265)
			(xy 155.252695 83.053725) (xy 155.243825 83.054995) (xy 155.240015 83.053725) (xy 155.208965 83.051825)
			(xy 155.201355 83.050555) (xy 155.195655 83.049925) (xy 155.191855 83.051195) (xy 155.167135 83.050555)
			(xy 155.166495 83.051195) (xy 155.131005 83.049925) (xy 154.642955 83.051195) (xy 154.639155 83.052455)
			(xy 154.603025 83.054355) (xy 154.589085 83.055625) (xy 154.582745 83.058165) (xy 154.572605 83.061965)
			(xy 154.566265 83.064505) (xy 154.561825 83.067675) (xy 154.558025 83.071475) (xy 154.555485 83.072745)
			(xy 154.552955 83.075275) (xy 154.550415 83.076545) (xy 154.548515 83.078445) (xy 154.547255 83.080985)
			(xy 154.541545 83.086685) (xy 154.539015 83.087955) (xy 154.535845 83.091125) (xy 154.534575 83.093655)
			(xy 154.528875 83.099365) (xy 154.526335 83.100625) (xy 154.523165 83.103795) (xy 154.521895 83.106335)
			(xy 154.516195 83.112035) (xy 154.513655 83.113305) (xy 154.511755 83.115205) (xy 154.510495 83.117745)
			(xy 154.503515 83.124715) (xy 154.500985 83.125985) (xy 154.499085 83.127885) (xy 154.497815 83.130415)
			(xy 154.492105 83.136125) (xy 154.489575 83.137395) (xy 154.486405 83.140565) (xy 154.485135 83.143095)
			(xy 154.479435 83.148805) (xy 154.476895 83.150065) (xy 154.474995 83.151975) (xy 154.473725 83.154505)
			(xy 154.468025 83.160205) (xy 154.465485 83.161475) (xy 154.462315 83.164645) (xy 154.461055 83.167185)
			(xy 154.456615 83.171615) (xy 154.454075 83.172885) (xy 154.450905 83.176055) (xy 154.449645 83.178595)
			(xy 154.443935 83.184295) (xy 154.441405 83.185565) (xy 154.438235 83.188735) (xy 154.436965 83.191265)
			(xy 154.432525 83.195705) (xy 154.429995 83.196975) (xy 154.425555 83.201405) (xy 154.421755 83.207745)
			(xy 154.415415 83.216615) (xy 154.414145 83.221685) (xy 154.412245 83.233735) (xy 154.408445 83.243875)
			(xy 154.406545 83.250845) (xy 154.405275 83.255915) (xy 154.403375 83.292045) (xy 154.402105 83.327535)
			(xy 154.401475 83.927765) (xy 154.091081 83.927765) (xy 154.089635 83.925235) (xy 154.083295 83.911285)
			(xy 154.076955 83.899875) (xy 154.070615 83.885935) (xy 154.065545 83.877065) (xy 154.057945 83.860585)
			(xy 154.056675 83.858045) (xy 154.050335 83.847905) (xy 154.047795 83.841565) (xy 154.044625 83.833325)
			(xy 154.037655 83.820015) (xy 154.036385 83.814945) (xy 154.033225 83.800365) (xy 154.026245 83.787065)
			(xy 154.023715 83.780725) (xy 154.012305 83.756635) (xy 154.011035 83.747765) (xy 154.009775 83.742695)
			(xy 154.006605 83.734455) (xy 154.004705 83.732555) (xy 154.000895 83.723675) (xy 153.998365 83.717335)
			(xy 153.988225 83.695795) (xy 153.986955 83.690725) (xy 153.985055 83.681215) (xy 153.982515 83.674875)
			(xy 153.975545 83.657755) (xy 153.974275 83.648885) (xy 153.969835 83.636845) (xy 153.966665 83.629875)
			(xy 153.964135 83.623535) (xy 153.962865 83.618465) (xy 153.959695 83.605155) (xy 153.957165 83.598815)
			(xy 153.953995 83.591845) (xy 153.951455 83.585505) (xy 153.950185 83.580435) (xy 153.948925 83.571565)
			(xy 153.942585 83.557615) (xy 153.940045 83.551275) (xy 153.938785 83.546205) (xy 153.935615 83.532895)
			(xy 153.933075 83.526555) (xy 153.931175 83.520855) (xy 153.928645 83.511985) (xy 153.927375 83.506915)
			(xy 153.926105 83.490435) (xy 153.924835 83.485365) (xy 153.922935 83.473315) (xy 153.921665 83.468245)
			(xy 153.919135 83.461905) (xy 153.914695 83.447335) (xy 153.913425 83.434655) (xy 153.912165 83.429585)
			(xy 153.910895 83.421975) (xy 153.907095 83.413105) (xy 153.903285 83.397895) (xy 153.902015 83.389015)
			(xy 153.900755 83.372535) (xy 153.899485 83.367475) (xy 153.897585 83.360495) (xy 153.894415 83.349725)
			(xy 153.890605 83.334515) (xy 153.887445 83.308525) (xy 153.882375 83.288235) (xy 153.880475 83.271135)
			(xy 153.878565 83.251485) (xy 153.877305 83.227395) (xy 153.876035 83.215985) (xy 153.874765 83.193165)
			(xy 153.873495 83.183025) (xy 153.872225 83.175425) (xy 153.870965 83.170355) (xy 153.869695 83.160205)
			(xy 153.868425 83.138655) (xy 153.867155 83.122175) (xy 153.865895 83.099365) (xy 153.864625 83.058795)
			(xy 153.862725 83.054355) (xy 153.860825 83.052455) (xy 153.855745 83.051195) (xy 153.845615 83.052455)
			(xy 153.843705 83.054355) (xy 153.841175 83.060695) (xy 153.062617 83.060695) (xy 153.061575 82.619555)
			(xy 153.057135 82.613855) (xy 153.052065 82.612585) (xy 152.648315 82.611955) (xy 152.640075 82.612585)
			(xy 152.636275 82.611315) (xy 152.615355 82.611955) (xy 152.609025 82.610685) (xy 152.604585 82.610055)
			(xy 152.600785 82.611315) (xy 152.591905 82.612585) (xy 152.576695 82.608785) (xy 152.543735 82.607515)
			(xy 152.531695 82.595475) (xy 152.530425 82.586605) (xy 152.529155 82.554905) (xy 152.527895 82.551105)
			(xy 152.526625 82.546035) (xy 152.527895 82.529555) (xy 152.526625 82.516875) (xy 152.527895 82.508005)
			(xy 152.526625 82.491525) (xy 152.527895 82.480115) (xy 152.526625 82.476315) (xy 152.527067 81.775305)
			(xy 153.391155 81.775305) (xy 153.391795 81.929325) (xy 153.391155 81.942635) (xy 153.392425 81.946435)
			(xy 153.393695 81.955315) (xy 153.395595 81.995245) (xy 153.397495 81.999685) (xy 153.402565 82.004745)
			(xy 153.403205 82.006655) (xy 153.405735 82.007915) (xy 153.408275 82.010455) (xy 153.417145 82.011725)
			(xy 153.455805 82.013625) (xy 153.462145 82.014895) (xy 153.477995 82.015525) (xy 153.481795 82.014255)
			(xy 153.494475 82.015525) (xy 153.572435 82.016155) (xy 153.583205 82.015525) (xy 153.587015 82.016795)
			(xy 153.607925 82.016155) (xy 153.623775 82.016795) (xy 153.627575 82.015525) (xy 153.638355 82.017425)
			(xy 153.678275 82.020595) (xy 153.690325 82.032635) (xy 153.691595 82.037705) (xy 153.691595 82.049115)
			(xy 153.691595 82.050385) (xy 153.692855 82.059255) (xy 153.694125 82.078275) (xy 153.695395 82.082075)
			(xy 153.694125 82.094755) (xy 153.695395 82.113765) (xy 153.694125 82.117575) (xy 153.695395 82.139125)
			(xy 153.694125 82.142925) (xy 153.695395 82.155595) (xy 153.696665 82.898445) (xy 153.699835 82.901615)
			(xy 153.704905 82.902875) (xy 153.713775 82.904145) (xy 153.850045 82.903515) (xy 153.864625 82.904145)
			(xy 153.868425 82.902875) (xy 153.888715 82.904145) (xy 153.892515 82.902875) (xy 153.901385 82.901615)
			(xy 153.941315 82.899705) (xy 153.947655 82.897175) (xy 153.956525 82.888295) (xy 153.959065 82.879425)
			(xy 153.960335 82.838865) (xy 153.961595 82.835055) (xy 153.962865 82.822385) (xy 153.961595 82.809705)
			(xy 153.962865 82.800835) (xy 153.962235 82.784985) (xy 153.963495 82.123275) (xy 153.964135 82.116305)
			(xy 153.962865 82.112495) (xy 153.964135 82.089685) (xy 153.962865 82.085875) (xy 153.964135 82.071935)
			(xy 153.965405 82.068135) (xy 153.966035 82.043415) (xy 153.965405 82.042775) (xy 153.966665 82.038975)
			(xy 153.967935 82.032635) (xy 153.979985 82.020595) (xy 153.988855 82.019325) (xy 154.008505 82.018695)
			(xy 154.011675 82.019325) (xy 154.015475 82.018065) (xy 154.026245 82.016155) (xy 154.033225 82.015525)
			(xy 154.037025 82.016795) (xy 154.060475 82.016155) (xy 154.072515 82.016795) (xy 154.076325 82.015525)
			(xy 154.093435 82.016155) (xy 154.159355 82.014895) (xy 154.166325 82.014255) (xy 154.170125 82.015525)
			(xy 154.189145 82.014255) (xy 154.192945 82.012985) (xy 154.235415 82.011085) (xy 154.251255 82.001585)
			(xy 154.254425 81.998415) (xy 154.259495 81.989535) (xy 154.263295 81.980665) (xy 154.265205 81.936935)
			(xy 154.266465 81.930595) (xy 154.267105 81.918555) (xy 154.265835 81.914745) (xy 154.267105 81.889395)
			(xy 154.265835 81.885595) (xy 154.267105 81.869115) (xy 154.265835 81.846295) (xy 154.267105 81.842485)
			(xy 154.265835 81.828545) (xy 154.264565 81.824745) (xy 154.262913 81.786715) (xy 154.376115 81.786715)
			(xy 154.377385 81.795585) (xy 154.378655 82.898445) (xy 154.383095 82.902875) (xy 154.395765 82.904145)
			(xy 154.625215 82.902875) (xy 154.629645 82.899705) (xy 154.632185 82.890835) (xy 154.632174 82.881325)
			(xy 154.802685 82.881325) (xy 154.803945 82.896535) (xy 154.807115 82.900975) (xy 154.809015 82.902875)
			(xy 154.814095 82.904145) (xy 155.063815 82.902875) (xy 155.068255 82.898445) (xy 155.069525 82.893365)
			(xy 155.070155 82.817945) (xy 155.069525 82.813505) (xy 155.070785 82.809705) (xy 155.069525 82.797025)
			(xy 155.070785 82.757735) (xy 155.070155 82.033275) (xy 155.071425 82.021865) (xy 155.073955 82.018065)
			(xy 155.080295 82.015525) (xy 155.283125 82.016795) (xy 155.287555 82.019955) (xy 155.288825 82.025035)
			(xy 155.289455 82.032005) (xy 155.288825 82.038975) (xy 155.290095 82.042775) (xy 155.289455 82.104255)
			(xy 155.290095 82.111235) (xy 155.288825 82.115035) (xy 155.289455 82.137225) (xy 155.288825 82.150525)
			(xy 155.290095 82.154335) (xy 155.289455 82.172715) (xy 155.290095 82.790695) (xy 155.290095 82.791955)
			(xy 155.291365 82.843935) (xy 155.292625 82.847735) (xy 155.293895 82.884495) (xy 155.300235 82.893365)
			(xy 155.303405 82.896535) (xy 155.305935 82.897805) (xy 155.312275 82.900345) (xy 155.355375 82.901615)
			(xy 155.359175 82.902875) (xy 155.368055 82.904145) (xy 155.387065 82.902875) (xy 155.390865 82.904145)
			(xy 155.525245 82.902875) (xy 155.530945 82.898445) (xy 155.532215 82.893365) (xy 155.533485 82.022495)
			(xy 155.537915 82.016795) (xy 155.546795 82.015525) (xy 155.597495 82.014255) (xy 155.601295 82.012985)
			(xy 155.611445 82.011725) (xy 155.613975 82.009185) (xy 155.616515 82.007915) (xy 155.622215 82.002215)
			(xy 155.623485 81.999685) (xy 155.626025 81.993345) (xy 155.627925 81.950875) (xy 155.629185 81.944535)
			(xy 155.629825 81.928695) (xy 155.628555 81.924885) (xy 155.629825 81.912215) (xy 155.628555 81.766435)
			(xy 155.626655 81.763265) (xy 155.620315 81.760725) (xy 154.889515 81.761365) (xy 154.874935 81.760725)
			(xy 154.871135 81.761995) (xy 154.858455 81.763265) (xy 154.822335 81.765165) (xy 154.817895 81.767065)
			(xy 154.808385 81.776575) (xy 154.807115 81.781645) (xy 154.805215 81.820305) (xy 154.803315 81.837425)
			(xy 154.802685 82.881325) (xy 154.632174 82.881325) (xy 154.630915 81.766435) (xy 154.626475 81.761995)
			(xy 154.617605 81.760725) (xy 154.410985 81.760725) (xy 154.383095 81.761995) (xy 154.378655 81.765165)
			(xy 154.377385 81.770235) (xy 154.376755 81.774675) (xy 154.377385 81.782915) (xy 154.376115 81.786715)
			(xy 154.262913 81.786715) (xy 154.262665 81.781005) (xy 154.260765 81.776575) (xy 154.255055 81.769605)
			(xy 154.247455 81.764535) (xy 154.202455 81.762625) (xy 154.196115 81.761365) (xy 154.180265 81.760725)
			(xy 154.176465 81.761995) (xy 154.163785 81.760725) (xy 153.396865 81.761995) (xy 153.392425 81.766435)
			(xy 153.391155 81.775305) (xy 152.527067 81.775305) (xy 152.527165 81.620655) (xy 154.333015 81.620655)
			(xy 154.336185 81.625085) (xy 154.345065 81.626355) (xy 154.355205 81.625085) (xy 154.362175 81.619385)
			(xy 154.364075 81.617485) (xy 154.372945 81.612415) (xy 154.376115 81.609245) (xy 154.377385 81.606705)
			(xy 154.383095 81.601005) (xy 154.385625 81.599735) (xy 154.388795 81.596565) (xy 154.390065 81.594035)
			(xy 154.395765 81.587065) (xy 154.398935 81.583895) (xy 154.400835 81.576925) (xy 154.403375 81.570585)
			(xy 154.410345 81.563605) (xy 154.411615 81.561075) (xy 154.417315 81.554105) (xy 154.419855 81.552835)
			(xy 154.426825 81.545865) (xy 154.428095 81.543325) (xy 154.432525 81.540155) (xy 154.439505 81.533185)
			(xy 154.440135 81.531285) (xy 154.442675 81.530015) (xy 154.450905 81.521775) (xy 154.452175 81.519245)
			(xy 154.454075 81.517335) (xy 154.456615 81.516075) (xy 154.462315 81.510365) (xy 154.463585 81.507835)
			(xy 154.465485 81.505935) (xy 154.468025 81.504665) (xy 154.474995 81.497685) (xy 154.476265 81.495155)
			(xy 154.478165 81.493255) (xy 154.480705 81.491985) (xy 154.487675 81.485015) (xy 154.488305 81.483115)
			(xy 154.490845 81.481845) (xy 154.500345 81.472335) (xy 154.500985 81.470435) (xy 154.503515 81.469175)
			(xy 154.511755 81.460935) (xy 154.513025 81.458395) (xy 154.514925 81.456495) (xy 154.517465 81.455225)
			(xy 154.519995 81.452695) (xy 154.522535 81.451425) (xy 154.527605 81.446355) (xy 154.533945 81.443815)
			(xy 154.542185 81.440645) (xy 154.547885 81.434945) (xy 154.550415 81.433675) (xy 154.552955 81.431135)
			(xy 154.555485 81.429875) (xy 154.558655 81.426705) (xy 154.559925 81.424165) (xy 154.564365 81.419735)
			(xy 154.566895 81.418465) (xy 154.571335 81.414025) (xy 154.572605 81.411495) (xy 154.577045 81.407055)
			(xy 154.579575 81.405785) (xy 154.582745 81.402615) (xy 154.584015 81.400085) (xy 154.589715 81.394375)
			(xy 154.592255 81.393115) (xy 154.595425 81.389945) (xy 154.596695 81.387405) (xy 154.602395 81.381705)
			(xy 154.604295 81.381065) (xy 154.604935 81.379165) (xy 154.606835 81.378535) (xy 154.608105 81.375995)
			(xy 154.615065 81.369025) (xy 154.617605 81.367755) (xy 154.622675 81.362685) (xy 154.625215 81.361415)
			(xy 154.637885 81.356345) (xy 154.644865 81.350645) (xy 154.648025 81.347475) (xy 154.650565 81.346205)
			(xy 154.679725 81.317055) (xy 154.682255 81.315785) (xy 154.684795 81.313245) (xy 154.687325 81.311985)
			(xy 154.693665 81.309445) (xy 154.702535 81.304375) (xy 154.705075 81.301835) (xy 154.707605 81.300575)
			(xy 154.711415 81.296775) (xy 154.713945 81.295505) (xy 154.717745 81.291705) (xy 154.720285 81.290435)
			(xy 154.722825 81.287895) (xy 154.729155 81.285365) (xy 154.734225 81.284095) (xy 154.741205 81.278385)
			(xy 154.744375 81.275215) (xy 154.746905 81.273955) (xy 154.749445 81.271415) (xy 154.751975 81.270145)
			(xy 154.757045 81.265075) (xy 154.759585 81.263805) (xy 154.772265 81.258735) (xy 154.774795 81.256205)
			(xy 154.777335 81.254935) (xy 154.782405 81.249865) (xy 154.784935 81.248595) (xy 154.791905 81.241625)
			(xy 154.793175 81.239095) (xy 154.796345 81.235925) (xy 154.798875 81.234655) (xy 154.802685 81.230855)
			(xy 154.805215 81.229585) (xy 154.807755 81.227055) (xy 154.814095 81.224515) (xy 154.822335 81.221345)
			(xy 154.829935 81.216275) (xy 154.836905 81.213105) (xy 154.845145 81.209935) (xy 154.852755 81.203595)
			(xy 154.855925 81.200425) (xy 154.858455 81.199165) (xy 154.865435 81.193455) (xy 154.867335 81.191555)
			(xy 154.876205 81.187755) (xy 154.892685 81.178875) (xy 154.901555 81.175075) (xy 154.907895 81.172545)
			(xy 154.916765 81.166205) (xy 154.923105 81.163665) (xy 154.928175 81.162395) (xy 154.937055 81.157325)
			(xy 154.950995 81.150985) (xy 154.957335 81.147185) (xy 154.962405 81.142115) (xy 154.964945 81.140845)
			(xy 154.967475 81.138315) (xy 154.970005 81.137045) (xy 154.975085 81.131975) (xy 154.977615 81.130705)
			(xy 154.989025 81.125635) (xy 154.997895 81.120565) (xy 155.014385 81.112965) (xy 155.033395 81.104085)
			(xy 155.038465 81.102815) (xy 155.047975 81.100915) (xy 155.054305 81.098385) (xy 155.062545 81.093945)
			(xy 155.075225 81.088875) (xy 155.077765 81.087605) (xy 155.087905 81.081265) (xy 155.094245 81.078735)
			(xy 155.156355 81.048315) (xy 155.162695 81.044505) (xy 155.167765 81.043245) (xy 155.176635 81.041975)
			(xy 155.181705 81.040705) (xy 155.198185 81.033095) (xy 155.207065 81.030565) (xy 155.220365 81.027395)
			(xy 155.234315 81.021055) (xy 155.245095 81.017885) (xy 155.254595 81.015985) (xy 155.260935 81.013445)
			(xy 155.274245 81.007745) (xy 155.284385 81.005205) (xy 155.292625 81.003305) (xy 155.306575 80.996975)
			(xy 155.317345 80.993805) (xy 155.330655 80.990635) (xy 155.337625 80.987465) (xy 155.346505 80.983665)
			(xy 155.356645 80.981125) (xy 155.364885 80.979225) (xy 155.371225 80.976695) (xy 155.379465 80.973525)
			(xy 155.389605 80.970985) (xy 155.404175 80.969085) (xy 155.428265 80.965285) (xy 155.438405 80.961475)
			(xy 155.445385 80.959575) (xy 155.455525 80.957045) (xy 155.471365 80.955135) (xy 155.476435 80.953875)
			(xy 155.482775 80.951335) (xy 155.491015 80.948165) (xy 155.501155 80.945635) (xy 155.518905 80.943095)
			(xy 155.523975 80.941825) (xy 155.536015 80.937395) (xy 155.542355 80.936125) (xy 155.553765 80.934855)
			(xy 155.560105 80.933585) (xy 155.570245 80.932325) (xy 155.582915 80.931055) (xy 155.598135 80.928515)
			(xy 155.604465 80.927255) (xy 155.615245 80.924085) (xy 155.639965 80.922185) (xy 155.660245 80.919645)
			(xy 155.677995 80.918375) (xy 155.695105 80.916475) (xy 155.705245 80.913935) (xy 155.717925 80.912675)
			(xy 155.734405 80.911405) (xy 155.797785 80.908865) (xy 155.861805 80.908235) (xy 155.995535 80.908865)
			(xy 155.999335 80.907605) (xy 156.069055 80.908865) (xy 156.120405 80.910775) (xy 156.143215 80.912035)
			(xy 156.160965 80.913305) (xy 156.167305 80.914575) (xy 156.177445 80.917105) (xy 156.211675 80.920915)
			(xy 156.231955 80.923445) (xy 156.245895 80.924715) (xy 156.251605 80.926615) (xy 156.260475 80.929155)
			(xy 156.270615 80.931685) (xy 156.289635 80.932955) (xy 156.293435 80.934225) (xy 156.301045 80.935495)
			(xy 156.304845 80.936755) (xy 156.318785 80.940555) (xy 156.327655 80.943095) (xy 156.344145 80.944365)
			(xy 156.353015 80.945635) (xy 156.361255 80.947535) (xy 156.366325 80.948805) (xy 156.376465 80.952605)
			(xy 156.383435 80.954505) (xy 156.388505 80.955775) (xy 156.404355 80.957675) (xy 156.414495 80.960205)
			(xy 156.420835 80.962745) (xy 156.431605 80.965915) (xy 156.436675 80.967185) (xy 156.452525 80.969085)
			(xy 156.460135 80.970355) (xy 156.470275 80.971615) (xy 156.475345 80.972885) (xy 156.485485 80.976695)
			(xy 156.493725 80.979855) (xy 156.498795 80.981125) (xy 156.508295 80.983025) (xy 156.514635 80.985565)
			(xy 156.527945 80.991265) (xy 156.533015 80.992535) (xy 156.542525 80.994435) (xy 156.552665 80.998235)
			(xy 156.565975 81.003945) (xy 156.571055 81.005205) (xy 156.580555 81.007115) (xy 156.586895 81.009645)
			(xy 156.604005 81.016615) (xy 156.612885 81.017885) (xy 156.624925 81.022325) (xy 156.638235 81.028025)
			(xy 156.643305 81.029295) (xy 156.656615 81.032465) (xy 156.682605 81.044505) (xy 156.701615 81.053385)
			(xy 156.713655 81.055285) (xy 156.719995 81.057825) (xy 156.730775 81.063525) (xy 156.739645 81.067325)
			(xy 156.761195 81.077465) (xy 156.766265 81.078735) (xy 156.776405 81.080005) (xy 156.797955 81.090145)
			(xy 156.811905 81.097745) (xy 156.825845 81.104085) (xy 156.828385 81.105355) (xy 156.835355 81.111065)
			(xy 156.839785 81.114225) (xy 156.846765 81.119935) (xy 156.849925 81.123105) (xy 156.852465 81.124365)
			(xy 156.861335 81.128175) (xy 156.869575 81.131345) (xy 156.877185 81.136415) (xy 156.884155 81.138315)
			(xy 156.889225 81.139585) (xy 156.898105 81.140845) (xy 156.919655 81.150985) (xy 156.928525 81.156055)
			(xy 156.935495 81.161765) (xy 156.937395 81.163665) (xy 156.939935 81.164935) (xy 156.946905 81.170635)
			(xy 156.950075 81.173805) (xy 156.964015 81.178875) (xy 156.971625 81.183945) (xy 156.980495 81.187755)
			(xy 156.991905 81.194085) (xy 156.996975 81.199165) (xy 156.999515 81.200425) (xy 157.006485 81.206135)
			(xy 157.009655 81.209305) (xy 157.015995 81.211835) (xy 157.024235 81.215005) (xy 157.026135 81.216905)
			(xy 157.042615 81.224515) (xy 157.051485 81.229585) (xy 157.054025 81.232125) (xy 157.056555 81.233385)
			(xy 157.073035 81.249865) (xy 157.075575 81.251135) (xy 157.083175 81.258735) (xy 157.095215 81.263175)
			(xy 157.099655 81.266345) (xy 157.106625 81.272055) (xy 157.114235 81.277125) (xy 157.119935 81.282825)
			(xy 157.126275 81.285365) (xy 157.131345 81.286625) (xy 157.142755 81.295505) (xy 157.149725 81.301205)
			(xy 157.151635 81.303105) (xy 157.154165 81.304375) (xy 157.157965 81.308175) (xy 157.164945 81.310075)
			(xy 157.175085 81.316415) (xy 157.178255 81.319585) (xy 157.180785 81.320855) (xy 157.207405 81.347475)
			(xy 157.209945 81.348745) (xy 157.217545 81.356345) (xy 157.226425 81.358885) (xy 157.232765 81.362685)
			(xy 157.239735 81.368395) (xy 157.244175 81.371565) (xy 157.249875 81.377265) (xy 157.251145 81.379805)
			(xy 157.254315 81.382965) (xy 157.256845 81.384235) (xy 157.260015 81.387405) (xy 157.261285 81.389945)
			(xy 157.266985 81.395645) (xy 157.269525 81.396915) (xy 157.276495 81.402615) (xy 157.279665 81.405785)
			(xy 157.287905 81.407685) (xy 157.294875 81.412125) (xy 157.298675 81.415925) (xy 157.301215 81.417195)
			(xy 157.303745 81.419735) (xy 157.306285 81.420995) (xy 157.308185 81.422895) (xy 157.309455 81.425435)
			(xy 157.331635 81.447615) (xy 157.333535 81.448255) (xy 157.334805 81.450785) (xy 157.391215 81.507195)
			(xy 157.393115 81.507835) (xy 157.394385 81.510365) (xy 157.439385 81.555365) (xy 157.441285 81.556005)
			(xy 157.442555 81.558535) (xy 157.462205 81.578185) (xy 157.464735 81.579455) (xy 157.467905 81.582625)
			(xy 157.469175 81.585155) (xy 157.474885 81.590865) (xy 157.477415 81.592135) (xy 157.480585 81.595305)
			(xy 157.481855 81.597835) (xy 157.487555 81.604805) (xy 157.489455 81.606705) (xy 157.491995 81.613045)
			(xy 157.495165 81.621285) (xy 157.500865 81.626995) (xy 157.502135 81.629525) (xy 157.504675 81.632065)
			(xy 157.505935 81.634595) (xy 157.510375 81.639035) (xy 157.512915 81.640305) (xy 157.517345 81.644735)
			(xy 157.518615 81.647275) (xy 157.523055 81.651715) (xy 157.525585 81.652975) (xy 157.530025 81.657415)
			(xy 157.531295 81.659955) (xy 157.535095 81.663755) (xy 157.536365 81.666285) (xy 157.538895 81.668825)
			(xy 157.543335 81.680865) (xy 157.546505 81.685305) (xy 157.551575 81.690375) (xy 157.552835 81.692905)
			(xy 157.579465 81.719535) (xy 157.580725 81.722065) (xy 157.585805 81.727135) (xy 157.587065 81.729675)
			(xy 157.589605 81.736005) (xy 157.594675 81.744885) (xy 157.600375 81.751855) (xy 157.602285 81.753755)
			(xy 157.603545 81.756295) (xy 157.607355 81.760095) (xy 157.608615 81.762625) (xy 157.612415 81.766435)
			(xy 157.614315 81.773405) (xy 157.616855 81.779745) (xy 157.623825 81.786715) (xy 157.625095 81.789245)
			(xy 157.633965 81.800655) (xy 157.636505 81.803195) (xy 157.637775 81.808265) (xy 157.644115 81.819675)
			(xy 157.649185 81.824745) (xy 157.650455 81.827285) (xy 157.659955 81.836785) (xy 157.661855 81.837425)
			(xy 157.663125 81.839955) (xy 157.666935 81.843755) (xy 157.668195 81.846295) (xy 157.671995 81.850095)
			(xy 157.674535 81.856435) (xy 157.677705 81.864675) (xy 157.682775 81.872285) (xy 157.687215 81.883055)
			(xy 157.692285 81.891935) (xy 157.697355 81.897005) (xy 157.698615 81.899535) (xy 157.701155 81.902075)
			(xy 157.702425 81.904605) (xy 157.707495 81.909675) (xy 157.708765 81.912215) (xy 157.712565 81.921085)
			(xy 157.720175 81.935025) (xy 157.723975 81.943905) (xy 157.729045 81.952775) (xy 157.734115 81.957845)
			(xy 157.735385 81.960385) (xy 157.741085 81.967355) (xy 157.744255 81.971795) (xy 157.746795 81.974325)
			(xy 157.749955 81.982565) (xy 157.752495 81.988905) (xy 157.758205 81.998415) (xy 157.761365 82.006655)
			(xy 157.763275 82.011085) (xy 157.768345 82.018695) (xy 157.772145 82.027565) (xy 157.774685 82.033905)
			(xy 157.781015 82.044045) (xy 157.784825 82.052925) (xy 157.806365 82.094755) (xy 157.810175 82.103625)
			(xy 157.813345 82.111865) (xy 157.815245 82.113765) (xy 157.819045 82.122645) (xy 157.820315 82.131515)
			(xy 157.821585 82.136585) (xy 157.824755 82.144825) (xy 157.830455 82.154335) (xy 157.831725 82.159405)
			(xy 157.855805 82.208835) (xy 157.857075 82.213915) (xy 157.858345 82.224055) (xy 157.867215 82.243065)
			(xy 157.869755 82.253215) (xy 157.871015 82.260815) (xy 157.876085 82.272225) (xy 157.879895 82.281095)
			(xy 157.882425 82.291235) (xy 157.883695 82.298845) (xy 157.890035 82.312785) (xy 157.892575 82.319125)
			(xy 157.893835 82.324195) (xy 157.895735 82.334975) (xy 157.902075 82.348915) (xy 157.905245 82.357155)
			(xy 157.906515 82.362225) (xy 157.907785 82.371095) (xy 157.914115 82.385045) (xy 157.916655 82.391385)
			(xy 157.919825 82.405965) (xy 157.923625 82.416105) (xy 157.926795 82.424345) (xy 157.928065 82.429415)
			(xy 157.929965 82.443985) (xy 157.932505 82.464275) (xy 157.935035 82.474415) (xy 157.938205 82.482655)
			(xy 157.942005 82.495335) (xy 157.943915 82.511175) (xy 157.945175 82.517515) (xy 157.948985 82.527655)
			(xy 157.952785 82.541595) (xy 157.954055 82.549205) (xy 157.956585 82.572025) (xy 157.959125 82.582165)
			(xy 157.962295 82.592935) (xy 157.964825 82.603085) (xy 157.966095 82.611955) (xy 157.967365 82.617025)
			(xy 157.968625 82.634765) (xy 157.969895 82.638575) (xy 157.974965 82.656325) (xy 157.978135 82.687375)
			(xy 157.979405 82.697515) (xy 157.980675 82.717805) (xy 157.982575 82.734915) (xy 157.985745 82.749495)
			(xy 157.987645 82.766605) (xy 157.989545 82.798935) (xy 157.990815 82.847105) (xy 157.992085 82.920625)
			(xy 157.995245 82.925065) (xy 157.997155 82.926965) (xy 158.002225 82.928235) (xy 158.021235 82.926965)
			(xy 158.025675 82.922525) (xy 158.026945 82.917455) (xy 158.025675 82.900975) (xy 158.020605 82.889565)
			(xy 158.019335 82.880695) (xy 158.017435 82.855975) (xy 158.016165 82.842035) (xy 158.013635 82.788785)
			(xy 158.012365 82.767245) (xy 158.011095 82.749495) (xy 158.009825 82.739355) (xy 158.008565 82.733015)
			(xy 158.007295 82.727945) (xy 158.006025 82.721605) (xy 158.003485 82.706395) (xy 158.000955 82.681035)
			(xy 157.998415 82.665825) (xy 157.997155 82.660755) (xy 157.995245 82.655055) (xy 157.993985 82.649985)
			(xy 157.992715 82.637305) (xy 157.991445 82.632235) (xy 157.988915 82.606885) (xy 157.987645 82.601815)
			(xy 157.986375 82.591675) (xy 157.983835 82.585335) (xy 157.980035 82.570115) (xy 157.978765 82.557445)
			(xy 157.977505 82.552375) (xy 157.976235 82.539695) (xy 157.974965 82.535895) (xy 157.973695 82.530825)
			(xy 157.969895 82.518145) (xy 157.968625 82.513075) (xy 157.966095 82.495335) (xy 157.964195 82.479485)
			(xy 157.962925 82.474415) (xy 157.959125 82.464275) (xy 157.955955 82.456035) (xy 157.953415 82.445885)
			(xy 157.952145 82.438285) (xy 157.945815 82.424345) (xy 157.943275 82.415465) (xy 157.941375 82.399625)
			(xy 157.940105 82.393285) (xy 157.935035 82.379345) (xy 157.931865 82.371095) (xy 157.929335 82.360955)
			(xy 157.927435 82.353985) (xy 157.924265 82.345745) (xy 157.920455 82.336875) (xy 157.917925 82.327995)
			(xy 157.914755 82.314695) (xy 157.907785 82.298845) (xy 157.905245 82.288705) (xy 157.903345 82.281725)
			(xy 157.899545 82.271585) (xy 157.895105 82.260815) (xy 157.892575 82.250675) (xy 157.891305 82.243065)
			(xy 157.884965 82.232925) (xy 157.883695 82.227855) (xy 157.869755 82.198705) (xy 157.868485 82.186025)
			(xy 157.855805 82.159405) (xy 157.849465 82.147995) (xy 157.843135 82.134055) (xy 157.836795 82.122645)
			(xy 157.830455 82.108695) (xy 157.821585 82.089685) (xy 157.819685 82.077645) (xy 157.817145 82.071305)
			(xy 157.800665 82.038345) (xy 157.788625 82.013625) (xy 157.777215 81.992075) (xy 157.772145 81.987005)
			(xy 157.770875 81.984465) (xy 157.765175 81.977495) (xy 157.760735 81.969255) (xy 157.759465 81.960385)
			(xy 157.758205 81.952775) (xy 157.754395 81.946435) (xy 157.750595 81.942635) (xy 157.749325 81.940095)
			(xy 157.740455 81.928695) (xy 157.735385 81.921085) (xy 157.733475 81.914115) (xy 157.727145 81.903975)
			(xy 157.723975 81.897005) (xy 157.720805 81.888765) (xy 157.714465 81.881155) (xy 157.712565 81.879255)
			(xy 157.711295 81.876715) (xy 157.705595 81.869745) (xy 157.702425 81.866575) (xy 157.701155 81.864045)
			(xy 157.698615 81.857705) (xy 157.692285 81.846295) (xy 157.685945 81.839955) (xy 157.684675 81.837425)
			(xy 157.680875 81.833615) (xy 157.679605 81.831085) (xy 157.677075 81.828545) (xy 157.674535 81.822215)
			(xy 157.671365 81.813965) (xy 157.664395 81.806995) (xy 157.663125 81.804465) (xy 157.657425 81.797485)
			(xy 157.654255 81.794325) (xy 157.650455 81.786715) (xy 157.650455 81.785445) (xy 157.644115 81.774035)
			(xy 157.639045 81.768965) (xy 157.637775 81.766435) (xy 157.621295 81.749955) (xy 157.620025 81.747415)
			(xy 157.616225 81.743615) (xy 157.613685 81.737275) (xy 157.610515 81.729035) (xy 157.604815 81.723335)
			(xy 157.603545 81.720795) (xy 157.599745 81.716995) (xy 157.598475 81.714465) (xy 157.594045 81.711295)
			(xy 157.588335 81.705585) (xy 157.587065 81.703055) (xy 157.583265 81.699245) (xy 157.581995 81.696715)
			(xy 157.579465 81.694175) (xy 157.576925 81.687835) (xy 157.573755 81.679595) (xy 157.566785 81.672625)
			(xy 157.565515 81.670085) (xy 157.550305 81.654885) (xy 157.549035 81.652345) (xy 157.543965 81.647275)
			(xy 157.542695 81.644735) (xy 157.540165 81.638405) (xy 157.538895 81.633335) (xy 157.533195 81.626355)
			(xy 157.530025 81.623185) (xy 157.528755 81.620655) (xy 157.520515 81.612415) (xy 157.517985 81.611145)
			(xy 157.514815 81.606705) (xy 157.498965 81.590865) (xy 157.496435 81.589595) (xy 157.493265 81.586425)
			(xy 157.491995 81.583895) (xy 157.486295 81.578185) (xy 157.483755 81.576925) (xy 157.480585 81.573755)
			(xy 157.479315 81.571215) (xy 157.475515 81.567415) (xy 157.474245 81.564875) (xy 157.469175 81.559805)
			(xy 157.466645 81.550935) (xy 157.462835 81.544595) (xy 157.457765 81.539525) (xy 157.456495 81.536985)
			(xy 157.450795 81.530015) (xy 157.443825 81.524315) (xy 157.442555 81.521775) (xy 157.438115 81.517335)
			(xy 157.435585 81.516075) (xy 157.431145 81.511635) (xy 157.429875 81.509095) (xy 157.425445 81.504665)
			(xy 157.422905 81.503395) (xy 157.419735 81.500225) (xy 157.418475 81.497685) (xy 157.414035 81.493255)
			(xy 157.411495 81.491985) (xy 157.407065 81.487555) (xy 157.405795 81.485015) (xy 157.401355 81.480575)
			(xy 157.398825 81.479315) (xy 157.394385 81.474875) (xy 157.393115 81.472335) (xy 157.388685 81.467905)
			(xy 157.386145 81.466635) (xy 157.382975 81.463465) (xy 157.381705 81.460935) (xy 157.377275 81.456495)
			(xy 157.374735 81.455225) (xy 157.367765 81.449525) (xy 157.364595 81.446355) (xy 157.350655 81.441285)
			(xy 157.345585 81.436205) (xy 157.343045 81.434945) (xy 157.340515 81.432405) (xy 157.337975 81.431135)
			(xy 157.333535 81.426705) (xy 157.332275 81.424165) (xy 157.329105 81.420995) (xy 157.326565 81.419735)
			(xy 157.322125 81.415295) (xy 157.320865 81.412755) (xy 157.316425 81.408325) (xy 157.313885 81.407055)
			(xy 157.308185 81.401355) (xy 157.306915 81.398815) (xy 157.291075 81.382965) (xy 157.288535 81.381705)
			(xy 157.286635 81.379805) (xy 157.285365 81.377265) (xy 157.278395 81.370295) (xy 157.275855 81.369025)
			(xy 157.269525 81.362685) (xy 157.266985 81.361415) (xy 157.260645 81.358885) (xy 157.255575 81.357615)
			(xy 157.248605 81.351915) (xy 157.245435 81.348745) (xy 157.242905 81.347475) (xy 157.227695 81.332265)
			(xy 157.225155 81.330995) (xy 157.218815 81.324655) (xy 157.213745 81.323385) (xy 157.205505 81.320215)
			(xy 157.199805 81.314515) (xy 157.197265 81.313245) (xy 157.194725 81.310715) (xy 157.192195 81.309445)
			(xy 157.185225 81.302475) (xy 157.183955 81.299935) (xy 157.179525 81.296775) (xy 157.175715 81.292965)
			(xy 157.173185 81.291705) (xy 157.170645 81.289165) (xy 157.168115 81.287895) (xy 157.161775 81.285365)
			(xy 157.152895 81.280295) (xy 157.150365 81.277755) (xy 157.147825 81.276485) (xy 157.132615 81.261275)
			(xy 157.130075 81.260005) (xy 157.122475 81.252405) (xy 157.116135 81.249865) (xy 157.111065 81.248595)
			(xy 157.088245 81.230855) (xy 157.084445 81.227055) (xy 157.079375 81.225785) (xy 157.071135 81.222615)
			(xy 157.067965 81.219445) (xy 157.065435 81.218175) (xy 157.060365 81.213105) (xy 157.057825 81.211835)
			(xy 157.051485 81.205495) (xy 157.048955 81.204235) (xy 157.040075 81.200425) (xy 157.031205 81.195355)
			(xy 157.026135 81.190285) (xy 157.023595 81.189015) (xy 157.021065 81.186485) (xy 157.018525 81.185215)
			(xy 157.012185 81.178875) (xy 157.005855 81.176345) (xy 156.997615 81.173175) (xy 156.988105 81.167465)
			(xy 156.981765 81.164935) (xy 156.970355 81.158595) (xy 156.966555 81.154795) (xy 156.964015 81.153525)
			(xy 156.957045 81.147825) (xy 156.952605 81.143385) (xy 156.946275 81.140845) (xy 156.938035 81.137685)
			(xy 156.930425 81.132605) (xy 156.923455 81.129445) (xy 156.914585 81.125635) (xy 156.912045 81.124365)
			(xy 156.904435 81.119305) (xy 156.895565 81.115495) (xy 156.887325 81.112325) (xy 156.885425 81.110425)
			(xy 156.882895 81.109155) (xy 156.868945 81.102815) (xy 156.857535 81.096485) (xy 156.843595 81.090145)
			(xy 156.822045 81.080005) (xy 156.816975 81.078735) (xy 156.806835 81.077465) (xy 156.797955 81.072395)
			(xy 156.789085 81.068595) (xy 156.780845 81.065425) (xy 156.773235 81.060355) (xy 156.751055 81.049575)
			(xy 156.716825 81.033095) (xy 156.707955 81.030565) (xy 156.699085 81.029295) (xy 156.672455 81.016615)
			(xy 156.653445 81.007745) (xy 156.644575 81.006475) (xy 156.632535 81.002045) (xy 156.626195 80.999505)
			(xy 156.619215 80.996335) (xy 156.614145 80.995065) (xy 156.600835 80.991905) (xy 156.594495 80.989365)
			(xy 156.587525 80.986195) (xy 156.581195 80.983665) (xy 156.576125 80.982395) (xy 156.566615 80.980495)
			(xy 156.556475 80.976695) (xy 156.549495 80.973525) (xy 156.543165 80.970985) (xy 156.534285 80.969715)
			(xy 156.522245 80.965285) (xy 156.514005 80.962115) (xy 156.507665 80.959575) (xy 156.498795 80.958305)
			(xy 156.493725 80.957045) (xy 156.479775 80.955775) (xy 156.468375 80.950705) (xy 156.462035 80.948165)
			(xy 156.451895 80.945635) (xy 156.444285 80.944365) (xy 156.432875 80.939295) (xy 156.426535 80.936755)
			(xy 156.417665 80.934225) (xy 156.401815 80.932325) (xy 156.395485 80.931055) (xy 156.385335 80.927255)
			(xy 156.378365 80.925345) (xy 156.373295 80.924085) (xy 156.357445 80.922185) (xy 156.343505 80.920915)
			(xy 156.320685 80.917105) (xy 156.315615 80.915845) (xy 156.308645 80.913935) (xy 156.303575 80.912675)
			(xy 156.285825 80.910135) (xy 156.268715 80.908235) (xy 156.261105 80.906965) (xy 156.250965 80.905695)
			(xy 156.244625 80.904435) (xy 156.239555 80.903165) (xy 156.232585 80.901265) (xy 156.217375 80.898725)
			(xy 156.185045 80.895555) (xy 156.167935 80.893655) (xy 156.159065 80.892395) (xy 156.152095 80.890485)
			(xy 156.145755 80.889225) (xy 156.128645 80.887315) (xy 156.104555 80.886055) (xy 156.088075 80.884785)
			(xy 156.078565 80.884155) (xy 156.072865 80.884785) (xy 156.069055 80.883515) (xy 156.043075 80.881615)
			(xy 156.030395 80.880345) (xy 156.016455 80.877815) (xy 156.006315 80.876545) (xy 155.983495 80.875275)
			(xy 155.969555 80.874015) (xy 155.945465 80.872745) (xy 155.911875 80.872105) (xy 155.908065 80.873375)
			(xy 155.873845 80.874645) (xy 155.870035 80.875915) (xy 155.840885 80.877185) (xy 155.837085 80.878445)
			(xy 155.832015 80.879715) (xy 155.815525 80.880985) (xy 155.810465 80.882245) (xy 155.783205 80.884155)
			(xy 155.778775 80.884785) (xy 155.774965 80.883515) (xy 155.769895 80.884785) (xy 155.736305 80.886685)
			(xy 155.718555 80.887955) (xy 155.710955 80.889225) (xy 155.704615 80.890485) (xy 155.699545 80.891755)
			(xy 155.682425 80.893655) (xy 155.677355 80.894925) (xy 155.650105 80.898095) (xy 155.632355 80.899365)
			(xy 155.626025 80.900625) (xy 155.620945 80.901895) (xy 155.613975 80.903795) (xy 155.608905 80.905065)
			(xy 155.582285 80.908865) (xy 155.565805 80.910135) (xy 155.562005 80.911405) (xy 155.549965 80.913305)
			(xy 155.544895 80.914575) (xy 155.534115 80.917745) (xy 155.520805 80.919645) (xy 155.503695 80.921545)
			(xy 155.482135 80.924085) (xy 155.475165 80.925985) (xy 155.460595 80.931685) (xy 155.455525 80.932955)
			(xy 155.442215 80.936125) (xy 155.435235 80.939295) (xy 155.428895 80.941825) (xy 155.420655 80.943725)
			(xy 155.414325 80.944995) (xy 155.399105 80.947535) (xy 155.394035 80.948805) (xy 155.383905 80.952605)
			(xy 155.375665 80.955775) (xy 155.362985 80.957045) (xy 155.354105 80.958305) (xy 155.349035 80.959575)
			(xy 155.340795 80.962745) (xy 155.334455 80.965285) (xy 155.326225 80.968445) (xy 155.321145 80.969715)
			(xy 155.311645 80.971615) (xy 155.305305 80.974155) (xy 155.298335 80.977325) (xy 155.291995 80.979855)
			(xy 155.286925 80.981125) (xy 155.273615 80.984295) (xy 155.267275 80.986825) (xy 155.253965 80.992535)
			(xy 155.248895 80.993805) (xy 155.239385 80.995705) (xy 155.226705 81.000775) (xy 155.219735 81.003945)
			(xy 155.210865 81.006475) (xy 155.200095 81.008375) (xy 155.186775 81.015355) (xy 155.177905 81.019155)
			(xy 155.156355 81.029295) (xy 155.147485 81.030565) (xy 155.140505 81.032465) (xy 155.114525 81.044505)
			(xy 155.105645 81.049575) (xy 155.091705 81.055915) (xy 155.080295 81.062255) (xy 155.066355 81.068595)
			(xy 155.044805 81.078735) (xy 155.032765 81.080635) (xy 155.026425 81.083175) (xy 155.015645 81.088875)
			(xy 155.009305 81.091415) (xy 154.967475 81.112965) (xy 154.954805 81.118035) (xy 154.947825 81.123735)
			(xy 154.944655 81.126905) (xy 154.942125 81.128175) (xy 154.926915 81.138315) (xy 154.921845 81.139585)
			(xy 154.909795 81.141485) (xy 154.902825 81.145925) (xy 154.899025 81.149725) (xy 154.890145 81.154795)
			(xy 154.885075 81.159865) (xy 154.882545 81.161135) (xy 154.871135 81.166205) (xy 154.859725 81.172545)
			(xy 154.848315 81.177615) (xy 154.841985 81.181415) (xy 154.836905 81.186485) (xy 154.834375 81.187755)
			(xy 154.831835 81.190285) (xy 154.829305 81.191555) (xy 154.825505 81.195355) (xy 154.822965 81.196625)
			(xy 154.820425 81.199165) (xy 154.815355 81.200425) (xy 154.803945 81.206765) (xy 154.798875 81.211835)
			(xy 154.796345 81.213105) (xy 154.792535 81.216905) (xy 154.790005 81.218175) (xy 154.786205 81.221975)
			(xy 154.783665 81.223245) (xy 154.777335 81.225785) (xy 154.772265 81.227055) (xy 154.764655 81.234655)
			(xy 154.762115 81.235925) (xy 154.750705 81.244795) (xy 154.748175 81.247325) (xy 154.741835 81.249865)
			(xy 154.736765 81.251135) (xy 154.729795 81.256835) (xy 154.726625 81.260005) (xy 154.724085 81.261275)
			(xy 154.707605 81.277755) (xy 154.705075 81.279025) (xy 154.701265 81.282825) (xy 154.694935 81.285365)
			(xy 154.686695 81.288535) (xy 154.683525 81.291705) (xy 154.680985 81.292965) (xy 154.675915 81.298035)
			(xy 154.673385 81.299305) (xy 154.669585 81.303105) (xy 154.667045 81.304375) (xy 154.663245 81.308175)
			(xy 154.649295 81.313245) (xy 154.641695 81.320855) (xy 154.639155 81.322125) (xy 154.632185 81.327825)
			(xy 154.630915 81.330365) (xy 154.625215 81.336065) (xy 154.622675 81.337335) (xy 154.619505 81.341775)
			(xy 154.612535 81.348745) (xy 154.610005 81.350015) (xy 154.604935 81.355085) (xy 154.602395 81.356345)
			(xy 154.596055 81.358885) (xy 154.587815 81.362055) (xy 154.579575 81.370295) (xy 154.577045 81.371565)
			(xy 154.573875 81.373465) (xy 154.572605 81.375995) (xy 154.534575 81.414025) (xy 154.533305 81.416565)
			(xy 154.530145 81.419735) (xy 154.527605 81.420995) (xy 154.520635 81.426705) (xy 154.517465 81.429875)
			(xy 154.503515 81.434945) (xy 154.498445 81.440015) (xy 154.495915 81.441285) (xy 154.493375 81.443815)
			(xy 154.490845 81.445085) (xy 154.486405 81.449525) (xy 154.485135 81.452055) (xy 154.480705 81.456495)
			(xy 154.478165 81.457765) (xy 154.473725 81.462195) (xy 154.472465 81.464735) (xy 154.469295 81.467905)
			(xy 154.466755 81.469175) (xy 154.461055 81.474875) (xy 154.459785 81.477415) (xy 154.456615 81.480575)
			(xy 154.454075 81.481845) (xy 154.449645 81.486285) (xy 154.448375 81.488815) (xy 154.445205 81.491985)
			(xy 154.442675 81.493255) (xy 154.436965 81.498955) (xy 154.435695 81.501495) (xy 154.432525 81.504665)
			(xy 154.429995 81.505935) (xy 154.425555 81.510365) (xy 154.424295 81.512905) (xy 154.421125 81.516075)
			(xy 154.418585 81.517335) (xy 154.412885 81.523045) (xy 154.411615 81.525575) (xy 154.408445 81.528745)
			(xy 154.405905 81.530015) (xy 154.400205 81.535725) (xy 154.398935 81.538255) (xy 154.396405 81.540795)
			(xy 154.395135 81.543325) (xy 154.391335 81.547125) (xy 154.386895 81.559175) (xy 154.383725 81.563605)
			(xy 154.378655 81.568685) (xy 154.377385 81.571215) (xy 154.374215 81.575655) (xy 154.371685 81.576925)
			(xy 154.362175 81.586425) (xy 154.361545 81.588325) (xy 154.359005 81.589595) (xy 154.336825 81.611775)
			(xy 154.335555 81.614315) (xy 154.333015 81.620655) (xy 152.527165 81.620655) (xy 152.527895 80.463295)
			(xy 152.529155 80.459495) (xy 152.531065 80.418285) (xy 152.532325 80.413215) (xy 152.536765 80.402445)
			(xy 152.539305 80.393575) (xy 152.543105 80.387235) (xy 152.550075 80.385335)
		)
		(stroke
			(width 0)
			(type default)
		)
		(fill yes)
		(layer "F.Cu")
	)
	(gr_arc
		(start 123.101095 82.603601)
		(mid 123.979777 80.482282)
		(end 126.101099 79.603605)
		(stroke
			(width 0.05)
			(type solid)
		)
		(layer "Edge.Cuts")
	)
	(gr_line
		(start 123.101105 127.403602)
		(end 123.101105 127.403605)
		(stroke
			(width 0.05)
			(type solid)
		)
		(layer "Edge.Cuts")
	)
	(gr_line
		(start 123.101105 127.403605)
		(end 123.101095 82.603601)
		(stroke
			(width 0.05)
			(type solid)
		)
		(layer "Edge.Cuts")
	)
	(gr_line
		(start 126.001105 79.603595)
		(end 170.901105 79.603605)
		(stroke
			(width 0.05)
			(type solid)
		)
		(layer "Edge.Cuts")
	)
	(gr_line
		(start 126.101099 79.603605)
		(end 126.101105 79.603605)
		(stroke
			(width 0.05)
			(type solid)
		)
		(layer "Edge.Cuts")
	)
	(gr_arc
		(start 126.101102 130.403605)
		(mid 123.979783 129.524923)
		(end 123.101105 127.403602)
		(stroke
			(width 0.05)
			(type solid)
		)
		(layer "Edge.Cuts")
	)
	(gr_line
		(start 126.101105 79.603605)
		(end 126.001105 79.603595)
		(stroke
			(width 0.05)
			(type solid)
		)
		(layer "Edge.Cuts")
	)
	(gr_arc
		(start 170.901105 79.603605)
		(mid 173.022425 80.482285)
		(end 173.901105 82.603605)
		(stroke
			(width 0.05)
			(type solid)
		)
		(layer "Edge.Cuts")
	)
	(gr_line
		(start 170.901105 130.403605)
		(end 126.101102 130.403605)
		(stroke
			(width 0.05)
			(type solid)
		)
		(layer "Edge.Cuts")
	)
	(gr_line
		(start 173.901105 82.603605)
		(end 173.901105 127.403605)
		(stroke
			(width 0.05)
			(type solid)
		)
		(layer "Edge.Cuts")
	)
	(gr_arc
		(start 173.901105 127.403605)
		(mid 173.022425 129.524925)
		(end 170.901105 130.403605)
		(stroke
			(width 0.05)
			(type solid)
		)
		(layer "Edge.Cuts")
	)
	(segment
		(start 145.116105 105.913605)
		(end 145.116105 105.128605)
		(width 0.2)
		(layer "B.Cu")
		(net "NetR5_1")
	)
	(segment
		(start 144.476105 106.403605)
		(end 144.626105 106.403605)
		(width 0.2)
		(layer "B.Cu")
		(net "NetR5_1")
	)
	(segment
		(start 144.026105 105.128605)
		(end 145.116105 105.128605)
		(width 0.2)
		(layer "B.Cu")
		(net "NetR5_1")
	)
	(segment
		(start 144.626105 106.403605)
		(end 145.116105 105.913605)
		(width 0.2)
		(layer "B.Cu")
		(net "NetR5_1")
	)
	(segment
		(start 145.116105 104.168605)
		(end 145.116105 103.053605)
		(width 0.2)
		(layer "B.Cu")
		(net "NetC9_1")
	)
	(segment
		(start 143.026105 106.178605)
		(end 143.026105 105.128605)
		(width 0.2)
		(layer "B.Cu")
		(net "NetC4_2")
	)
	(segment
		(start 143.026105 107.328605)
		(end 143.026105 106.178605)
		(width 0.2)
		(layer "B.Cu")
		(net "NetC4_2")
	)
	(segment
		(start 144.001105 106.853605)
		(end 144.476105 106.853605)
		(width 0.2)
		(layer "B.Cu")
		(net "NetC4_2")
	)
	(segment
		(start 143.026105 107.328605)
		(end 143.526105 107.328605)
		(width 0.2)
		(layer "B.Cu")
		(net "NetC4_2")
	)
	(arc
		(start 143.726105 107.128605)
		(mid 143.667526 107.270026)
		(end 143.526105 107.328605)
		(width 0.2)
		(layer "B.Cu")
		(net "NetC4_2")
	)
	(arc
		(start 143.726105 107.128605)
		(mid 143.806651 106.934151)
		(end 144.001105 106.853605)
		(width 0.2)
		(layer "B.Cu")
		(net "NetC4_2")
	)
	(segment
		(start 146.176105 107.303605)
		(end 148.526105 107.303605)
		(width 0.35)
		(layer "B.Cu")
		(net "SW")
	)
	(segment
		(start 149.276105 108.553605)
		(end 149.276105 108.053605)
		(width 0.35)
		(layer "B.Cu")
		(net "SW")
	)
	(segment
		(start 148.526105 107.303605)
		(end 149.276105 108.053605)
		(width 0.35)
		(layer "B.Cu")
		(net "SW")
	)
	(segment
		(start 145.531135 107.303605)
		(end 146.176105 107.303605)
		(width 0.35)
		(layer "B.Cu")
		(net "SW")
	)
	(segment
		(start 145.326105 107.508625)
		(end 145.531135 107.303605)
		(width 0.35)
		(layer "B.Cu")
		(net "SW")
	)
	(segment
		(start 145.326105 108.491105)
		(end 145.326105 107.508625)
		(width 0.35)
		(layer "B.Cu")
		(net "SW")
	)
	(segment
		(start 147.301105 105.078605)
		(end 147.301105 104.168605)
		(width 0.4)
		(layer "B.Cu")
		(net "SW")
	)
	(segment
		(start 145.326105 109.253605)
		(end 145.326105 108.491105)
		(width 0.35)
		(layer "B.Cu")
		(net "SW")
	)
	(arc
		(start 147.676105 105.453605)
		(mid 147.41094 105.34377)
		(end 147.301105 105.078605)
		(width 0.4)
		(layer "B.Cu")
		(net "SW")
	)
	(segment
		(start 146.841105 106.603605)
		(end 146.841105 105.843605)
		(width 0.3)
		(layer "B.Cu")
		(net "NetC3_1")
	)
	(segment
		(start 146.176105 106.853605)
		(end 146.591105 106.853605)
		(width 0.2)
		(layer "B.Cu")
		(net "NetC3_1")
	)
	(segment
		(start 146.381105 105.383605)
		(end 146.381105 104.168605)
		(width 0.3)
		(layer "B.Cu")
		(net "NetC3_1")
	)
	(arc
		(start 146.841105 106.603605)
		(mid 146.767882 106.780382)
		(end 146.591105 106.853605)
		(width 0.2)
		(layer "B.Cu")
		(net "NetC3_1")
	)
	(arc
		(start 146.601105 105.603605)
		(mid 146.770811 105.673899)
		(end 146.841105 105.843605)
		(width 0.3)
		(layer "B.Cu")
		(net "NetC3_1")
	)
	(arc
		(start 146.601105 105.603605)
		(mid 146.445542 105.539168)
		(end 146.381105 105.383605)
		(width 0.3)
		(layer "B.Cu")
		(net "NetC3_1")
	)
	(segment
		(start 137.561105 107.001505)
		(end 137.561105 89.743605)
		(width 0.2)
		(layer "In1.Cu")
		(net "TX")
	)
	(segment
		(start 133.287105 82.013605)
		(end 134.867955 83.594455)
		(width 0.2)
		(layer "In1.Cu")
		(net "TX")
	)
	(segment
		(start 135.261105 85.491505)
		(end 135.261105 84.543605)
		(width 0.2)
		(layer "In1.Cu")
		(net "TX")
	)
	(segment
		(start 136.005055 87.287555)
		(end 136.924705 88.207205)
		(width 0.2)
		(layer "In1.Cu")
		(net "TX")
	)
	(segment
		(start 132.991105 112.623605)
		(end 136.817155 108.797555)
		(width 0.2)
		(layer "In1.Cu")
		(net "TX")
	)
	(arc
		(start 137.561105 107.001505)
		(mid 137.367759 107.973521)
		(end 136.817156 108.797556)
		(width 0.2)
		(layer "In1.Cu")
		(net "TX")
	)
	(arc
		(start 136.924707 88.207203)
		(mid 137.395711 88.91211)
		(end 137.561106 89.743605)
		(width 0.2)
		(layer "In1.Cu")
		(net "TX")
	)
	(arc
		(start 136.005054 87.287556)
		(mid 135.454451 86.463521)
		(end 135.261105 85.491505)
		(width 0.2)
		(layer "In1.Cu")
		(net "TX")
	)
	(arc
		(start 134.867954 83.594456)
		(mid 135.158928 84.029929)
		(end 135.261104 84.543605)
		(width 0.2)
		(layer "In1.Cu")
		(net "TX")
	)
	(segment
		(start 136.335105 85.060505)
		(end 136.335105 81.993605)
		(width 0.2)
		(layer "In1.Cu")
		(net "RX")
	)
	(segment
		(start 137.800955 87.578455)
		(end 137.801555 87.579055)
		(width 0.2)
		(layer "In1.Cu")
		(net "RX")
	)
	(segment
		(start 138.626105 89.570245)
		(end 138.626105 89.570305)
		(width 0.2)
		(layer "In1.Cu")
		(net "RX")
	)
	(segment
		(start 138.626105 111.016505)
		(end 138.626105 89.570305)
		(width 0.2)
		(layer "In1.Cu")
		(net "RX")
	)
	(segment
		(start 137.079045 86.856555)
		(end 137.800955 87.578455)
		(width 0.2)
		(layer "In1.Cu")
		(net "RX")
	)
	(segment
		(start 132.991105 117.703605)
		(end 137.882155 112.812555)
		(width 0.2)
		(layer "In1.Cu")
		(net "RX")
	)
	(arc
		(start 137.079054 86.856556)
		(mid 136.528451 86.032521)
		(end 136.335105 85.060505)
		(width 0.2)
		(layer "In1.Cu")
		(net "RX")
	)
	(arc
		(start 138.626105 111.016505)
		(mid 138.432759 111.988521)
		(end 137.882156 112.812556)
		(width 0.2)
		(layer "In1.Cu")
		(net "RX")
	)
	(arc
		(start 137.801549 87.579051)
		(mid 138.411987 88.492586)
		(end 138.626105 89.570239)
		(width 0.2)
		(layer "In1.Cu")
		(net "RX")
	)
	(segment
		(start 166.011105 92.303605)
		(end 168.057155 90.257555)
		(width 0.185)
		(layer "B.Cu")
		(net "RF_OUTPUT")
	)
	(segment
		(start 168.801105 88.461505)
		(end 168.801105 84.703605)
		(width 0.185)
		(layer "B.Cu")
		(net "RF_OUTPUT")
	)
	(arc
		(start 168.801105 88.461505)
		(mid 168.607759 89.433521)
		(end 168.057156 90.257556)
		(width 0.185)
		(layer "B.Cu")
		(net "RF_OUTPUT")
	)
	(segment
		(start 142.431105 86.097975)
		(end 142.431105 86.096965)
		(width 0.2)
		(layer "In1.Cu")
		(net "1PPS_OUT")
	)
	(segment
		(start 142.431105 86.096965)
		(end 142.431105 81.993605)
		(width 0.2)
		(layer "In1.Cu")
		(net "1PPS_OUT")
	)
	(segment
		(start 142.970655 87.398175)
		(end 142.970655 87.398175)
		(width 0.2)
		(layer "In1.Cu")
		(net "1PPS_OUT")
	)
	(segment
		(start 150.392235 93.953605)
		(end 156.024735 93.953605)
		(width 0.2)
		(layer "In1.Cu")
		(net "1PPS_OUT")
	)
	(segment
		(start 142.970655 87.398175)
		(end 148.913175 93.340675)
		(width 0.2)
		(layer "In1.Cu")
		(net "1PPS_OUT")
	)
	(segment
		(start 158.545055 94.997555)
		(end 166.011105 102.463605)
		(width 0.2)
		(layer "In1.Cu")
		(net "1PPS_OUT")
	)
	(arc
		(start 156.024728 93.953605)
		(mid 157.388715 94.22492)
		(end 158.545047 94.997558)
		(width 0.2)
		(layer "In1.Cu")
		(net "1PPS_OUT")
	)
	(arc
		(start 142.970652 87.398174)
		(mid 142.571335 86.801827)
		(end 142.431095 86.097969)
		(width 0.2)
		(layer "In1.Cu")
		(net "1PPS_OUT")
	)
	(arc
		(start 150.392229 93.953605)
		(mid 149.591769 93.794173)
		(end 148.913175 93.34067)
		(width 0.2)
		(layer "In1.Cu")
		(net "1PPS_OUT")
	)
	(segment
		(start 167.951105 109.378605)
		(end 167.951105 107.978605)
		(width 0.2)
		(layer "B.Cu")
		(net "1PPS_IN")
	)
	(segment
		(start 166.011105 107.543605)
		(end 167.516105 107.543605)
		(width 0.2)
		(layer "B.Cu")
		(net "1PPS_IN")
	)
	(arc
		(start 167.516105 107.543605)
		(mid 167.823696 107.671014)
		(end 167.951105 107.978605)
		(width 0.2)
		(layer "B.Cu")
		(net "1PPS_IN")
	)
	(segment
		(start 155.988825 97.521325)
		(end 166.011105 107.543605)
		(width 0.2)
		(layer "In1.Cu")
		(net "1PPS_IN")
	)
	(segment
		(start 140.127055 88.179555)
		(end 147.476105 95.528605)
		(width 0.2)
		(layer "In1.Cu")
		(net "1PPS_IN")
	)
	(segment
		(start 139.383105 86.383495)
		(end 139.383105 81.993605)
		(width 0.2)
		(layer "In1.Cu")
		(net "1PPS_IN")
	)
	(segment
		(start 150.431245 96.753605)
		(end 154.136805 96.753605)
		(width 0.2)
		(layer "In1.Cu")
		(net "1PPS_IN")
	)
	(arc
		(start 150.431244 96.753604)
		(mid 148.831923 96.434805)
		(end 147.476097 95.528607)
		(width 0.2)
		(layer "In1.Cu")
		(net "1PPS_IN")
	)
	(arc
		(start 154.136798 96.753605)
		(mid 155.13922 96.953141)
		(end 155.988825 97.521328)
		(width 0.2)
		(layer "In1.Cu")
		(net "1PPS_IN")
	)
	(arc
		(start 140.127054 88.179546)
		(mid 139.576451 87.355511)
		(end 139.383105 86.383495)
		(width 0.2)
		(layer "In1.Cu")
		(net "1PPS_IN")
	)
	(segment
		(start 168.841105 105.003605)
		(end 172.801105 105.003605)
		(width 1)
		(layer "F.Cu")
		(net "GND")
	)
	(via
		(at 163.461105 81.343605)
		(size 0.6)
		(drill 0.3)
		(layers "F.Cu" "B.Cu")
		(tenting
			(front yes)
			(back yes)
		)
		(net "GND")
	)
	(via
		(at 172.661105 84.843605)
		(size 0.6)
		(drill 0.3)
		(layers "F.Cu" "B.Cu")
		(tenting
			(front yes)
			(back yes)
		)
		(net "GND")
	)
	(via
		(at 147.176105 112.953605)
		(size 0.6)
		(drill 0.3)
		(layers "F.Cu" "B.Cu")
		(tenting
			(front yes)
			(back yes)
		)
		(net "GND")
	)
	(via
		(at 149.276105 117.553605)
		(size 0.6)
		(drill 0.3)
		(layers "F.Cu" "B.Cu")
		(tenting
			(front yes)
			(back yes)
		)
		(net "GND")
	)
	(via
		(at 147.176105 114.253605)
		(size 0.6)
		(drill 0.3)
		(layers "F.Cu" "B.Cu")
		(tenting
			(front yes)
			(back yes)
		)
		(net "GND")
	)
	(via
		(at 158.661105 128.843605)
		(size 0.6)
		(drill 0.3)
		(layers "F.Cu" "B.Cu")
		(tenting
			(front yes)
			(back yes)
		)
		(net "GND")
	)
	(via
		(at 147.176105 115.553605)
		(size 0.6)
		(drill 0.3)
		(layers "F.Cu" "B.Cu")
		(tenting
			(front yes)
			(back yes)
		)
		(net "GND")
	)
	(via
		(at 172.661105 112.843605)
		(size 0.6)
		(drill 0.3)
		(layers "F.Cu" "B.Cu")
		(tenting
			(front yes)
			(back yes)
		)
		(net "GND")
	)
	(via
		(at 170.386105 86.428605)
		(size 0.6)
		(drill 0.3)
		(layers "F.Cu" "B.Cu")
		(tenting
			(front yes)
			(back yes)
		)
		(net "GND")
	)
	(via
		(at 140.906105 85.078605)
		(size 0.6)
		(drill 0.3)
		(layers "F.Cu" "B.Cu")
		(tenting
			(front yes)
			(back yes)
		)
		(net "GND")
	)
	(via
		(at 160.661105 128.843605)
		(size 0.6)
		(drill 0.3)
		(layers "F.Cu" "B.Cu")
		(tenting
			(front yes)
			(back yes)
		)
		(net "GND")
	)
	(via
		(at 142.661105 129.343605)
		(size 0.6)
		(drill 0.3)
		(layers "F.Cu" "B.Cu")
		(tenting
			(front yes)
			(back yes)
		)
		(net "GND")
	)
	(via
		(at 146.976105 109.360905)
		(size 0.6)
		(drill 0.3)
		(layers "F.Cu" "B.Cu")
		(tenting
			(front yes)
			(back yes)
		)
		(net "GND")
	)
	(via
		(at 149.276105 115.053605)
		(size 0.6)
		(drill 0.3)
		(layers "F.Cu" "B.Cu")
		(tenting
			(front yes)
			(back yes)
		)
		(net "GND")
	)
	(via
		(at 144.045805 103.778605)
		(size 0.6)
		(drill 0.3)
		(layers "F.Cu" "B.Cu")
		(tenting
			(front yes)
			(back yes)
		)
		(net "GND")
	)
	(via
		(at 153.961105 86.443605)
		(size 0.6)
		(drill 0.3)
		(layers "F.Cu" "B.Cu")
		(tenting
			(front yes)
			(back yes)
		)
		(net "GND")
	)
	(via
		(at 141.151105 107.328605)
		(size 0.6)
		(drill 0.3)
		(layers "F.Cu" "B.Cu")
		(tenting
			(front yes)
			(back yes)
		)
		(net "GND")
	)
	(via
		(at 149.276105 118.578605)
		(size 0.6)
		(drill 0.3)
		(layers "F.Cu" "B.Cu")
		(tenting
			(front yes)
			(back yes)
		)
		(net "GND")
	)
	(via
		(at 128.661105 129.343605)
		(size 0.6)
		(drill 0.3)
		(layers "F.Cu" "B.Cu")
		(tenting
			(front yes)
			(back yes)
		)
		(net "GND")
	)
	(via
		(at 147.176105 117.953605)
		(size 0.6)
		(drill 0.3)
		(layers "F.Cu" "B.Cu")
		(tenting
			(front yes)
			(back yes)
		)
		(net "GND")
	)
	(via
		(at 172.661105 100.843605)
		(size 0.6)
		(drill 0.3)
		(layers "F.Cu" "B.Cu")
		(tenting
			(front yes)
			(back yes)
		)
		(net "GND")
	)
	(via
		(at 172.661105 96.843605)
		(size 0.6)
		(drill 0.3)
		(layers "F.Cu" "B.Cu")
		(tenting
			(front yes)
			(back yes)
		)
		(net "GND")
	)
	(via
		(at 172.661105 106.843605)
		(size 0.6)
		(drill 0.3)
		(layers "F.Cu" "B.Cu")
		(tenting
			(front yes)
			(back yes)
		)
		(net "GND")
	)
	(via
		(at 172.661105 86.843605)
		(size 0.6)
		(drill 0.3)
		(layers "F.Cu" "B.Cu")
		(tenting
			(front yes)
			(back yes)
		)
		(net "GND")
	)
	(via
		(at 147.176105 116.753605)
		(size 0.6)
		(drill 0.3)
		(layers "F.Cu" "B.Cu")
		(tenting
			(front yes)
			(back yes)
		)
		(net "GND")
	)
	(via
		(at 130.661105 129.343605)
		(size 0.6)
		(drill 0.3)
		(layers "F.Cu" "B.Cu")
		(tenting
			(front yes)
			(back yes)
		)
		(net "GND")
	)
	(via
		(at 132.661105 129.343605)
		(size 0.6)
		(drill 0.3)
		(layers "F.Cu" "B.Cu")
		(tenting
			(front yes)
			(back yes)
		)
		(net "GND")
	)
	(via
		(at 172.661105 102.843605)
		(size 0.6)
		(drill 0.3)
		(layers "F.Cu" "B.Cu")
		(tenting
			(front yes)
			(back yes)
		)
		(net "GND")
	)
	(via
		(at 149.276105 116.353605)
		(size 0.6)
		(drill 0.3)
		(layers "F.Cu" "B.Cu")
		(tenting
			(front yes)
			(back yes)
		)
		(net "GND")
	)
	(via
		(at 125.161105 91.343605)
		(size 0.6)
		(drill 0.3)
		(layers "F.Cu" "B.Cu")
		(tenting
			(front yes)
			(back yes)
		)
		(net "GND")
	)
	(via
		(at 125.161105 101.343605)
		(size 0.6)
		(drill 0.3)
		(layers "F.Cu" "B.Cu")
		(tenting
			(front yes)
			(back yes)
		)
		(net "GND")
	)
	(via
		(at 145.736105 111.453605)
		(size 0.6)
		(drill 0.3)
		(layers "F.Cu" "B.Cu")
		(tenting
			(front yes)
			(back yes)
		)
		(net "GND")
	)
	(via
		(at 125.161105 87.343605)
		(size 0.6)
		(drill 0.3)
		(layers "F.Cu" "B.Cu")
		(tenting
			(front yes)
			(back yes)
		)
		(net "GND")
	)
	(via
		(at 150.220295 113.053605)
		(size 0.6)
		(drill 0.3)
		(layers "F.Cu" "B.Cu")
		(tenting
			(front yes)
			(back yes)
		)
		(net "GND")
	)
	(via
		(at 172.661105 124.843605)
		(size 0.6)
		(drill 0.3)
		(layers "F.Cu" "B.Cu")
		(tenting
			(front yes)
			(back yes)
		)
		(net "GND")
	)
	(via
		(at 146.076105 109.647355)
		(size 0.6)
		(drill 0.3)
		(layers "F.Cu" "B.Cu")
		(tenting
			(front yes)
			(back yes)
		)
		(net "GND")
	)
	(via
		(at 125.161105 97.343605)
		(size 0.6)
		(drill 0.3)
		(layers "F.Cu" "B.Cu")
		(tenting
			(front yes)
			(back yes)
		)
		(net "GND")
	)
	(via
		(at 172.661105 104.843605)
		(size 0.6)
		(drill 0.3)
		(layers "F.Cu" "B.Cu")
		(tenting
			(front yes)
			(back yes)
		)
		(net "GND")
	)
	(via
		(at 140.661105 129.343605)
		(size 0.6)
		(drill 0.3)
		(layers "F.Cu" "B.Cu")
		(tenting
			(front yes)
			(back yes)
		)
		(net "GND")
	)
	(via
		(at 154.661105 128.843605)
		(size 0.6)
		(drill 0.3)
		(layers "F.Cu" "B.Cu")
		(tenting
			(front yes)
			(back yes)
		)
		(net "GND")
	)
	(via
		(at 151.501105 81.329775)
		(size 0.6)
		(drill 0.3)
		(layers "F.Cu" "B.Cu")
		(tenting
			(front yes)
			(back yes)
		)
		(net "GND")
	)
	(via
		(at 152.661105 128.843605)
		(size 0.6)
		(drill 0.3)
		(layers "F.Cu" "B.Cu")
		(tenting
			(front yes)
			(back yes)
		)
		(net "GND")
	)
	(via
		(at 168.661105 128.843605)
		(size 0.6)
		(drill 0.3)
		(layers "F.Cu" "B.Cu")
		(tenting
			(front yes)
			(back yes)
		)
		(net "GND")
	)
	(via
		(at 146.976105 108.491105)
		(size 0.6)
		(drill 0.3)
		(layers "F.Cu" "B.Cu")
		(tenting
			(front yes)
			(back yes)
		)
		(net "GND")
	)
	(via
		(at 172.661105 98.843605)
		(size 0.6)
		(drill 0.3)
		(layers "F.Cu" "B.Cu")
		(tenting
			(front yes)
			(back yes)
		)
		(net "GND")
	)
	(via
		(at 125.161105 85.343605)
		(size 0.6)
		(drill 0.3)
		(layers "F.Cu" "B.Cu")
		(tenting
			(front yes)
			(back yes)
		)
		(net "GND")
	)
	(via
		(at 150.620815 105.328605)
		(size 0.6)
		(drill 0.3)
		(layers "F.Cu" "B.Cu")
		(tenting
			(front yes)
			(back yes)
		)
		(net "GND")
	)
	(via
		(at 168.841105 82.578605)
		(size 0.6)
		(drill 0.3)
		(layers "F.Cu" "B.Cu")
		(tenting
			(front yes)
			(back yes)
		)
		(net "GND")
	)
	(via
		(at 125.161105 99.343605)
		(size 0.6)
		(drill 0.3)
		(layers "F.Cu" "B.Cu")
		(tenting
			(front yes)
			(back yes)
		)
		(net "GND")
	)
	(via
		(at 125.161105 93.343605)
		(size 0.6)
		(drill 0.3)
		(layers "F.Cu" "B.Cu")
		(tenting
			(front yes)
			(back yes)
		)
		(net "GND")
	)
	(via
		(at 172.661105 122.843605)
		(size 0.6)
		(drill 0.3)
		(layers "F.Cu" "B.Cu")
		(tenting
			(front yes)
			(back yes)
		)
		(net "GND")
	)
	(via
		(at 151.461105 86.443605)
		(size 0.6)
		(drill 0.3)
		(layers "F.Cu" "B.Cu")
		(tenting
			(front yes)
			(back yes)
		)
		(net "GND")
	)
	(via
		(at 125.161105 95.343605)
		(size 0.6)
		(drill 0.3)
		(layers "F.Cu" "B.Cu")
		(tenting
			(front yes)
			(back yes)
		)
		(net "GND")
	)
	(via
		(at 172.661105 88.843605)
		(size 0.6)
		(drill 0.3)
		(layers "F.Cu" "B.Cu")
		(tenting
			(front yes)
			(back yes)
		)
		(net "GND")
	)
	(via
		(at 172.661105 110.843605)
		(size 0.6)
		(drill 0.3)
		(layers "F.Cu" "B.Cu")
		(tenting
			(front yes)
			(back yes)
		)
		(net "GND")
	)
	(via
		(at 125.161105 89.343605)
		(size 0.6)
		(drill 0.3)
		(layers "F.Cu" "B.Cu")
		(tenting
			(front yes)
			(back yes)
		)
		(net "GND")
	)
	(via
		(at 125.161105 107.343605)
		(size 0.6)
		(drill 0.3)
		(layers "F.Cu" "B.Cu")
		(tenting
			(front yes)
			(back yes)
		)
		(net "GND")
	)
	(via
		(at 172.661105 116.843605)
		(size 0.6)
		(drill 0.3)
		(layers "F.Cu" "B.Cu")
		(tenting
			(front yes)
			(back yes)
		)
		(net "GND")
	)
	(via
		(at 151.570815 105.303605)
		(size 0.6)
		(drill 0.3)
		(layers "F.Cu" "B.Cu")
		(tenting
			(front yes)
			(back yes)
		)
		(net "GND")
	)
	(via
		(at 152.520815 105.303605)
		(size 0.6)
		(drill 0.3)
		(layers "F.Cu" "B.Cu")
		(tenting
			(front yes)
			(back yes)
		)
		(net "GND")
	)
	(via
		(at 160.961105 86.443605)
		(size 0.6)
		(drill 0.3)
		(layers "F.Cu" "B.Cu")
		(tenting
			(front yes)
			(back yes)
		)
		(net "GND")
	)
	(via
		(at 138.661105 129.343605)
		(size 0.6)
		(drill 0.3)
		(layers "F.Cu" "B.Cu")
		(tenting
			(front yes)
			(back yes)
		)
		(net "GND")
	)
	(via
		(at 140.906105 84.128605)
		(size 0.6)
		(drill 0.3)
		(layers "F.Cu" "B.Cu")
		(tenting
			(front yes)
			(back yes)
		)
		(net "GND")
	)
	(via
		(at 125.161105 103.343605)
		(size 0.6)
		(drill 0.3)
		(layers "F.Cu" "B.Cu")
		(tenting
			(front yes)
			(back yes)
		)
		(net "GND")
	)
	(via
		(at 146.976105 110.243605)
		(size 0.6)
		(drill 0.3)
		(layers "F.Cu" "B.Cu")
		(tenting
			(front yes)
			(back yes)
		)
		(net "GND")
	)
	(via
		(at 166.661105 128.843605)
		(size 0.6)
		(drill 0.3)
		(layers "F.Cu" "B.Cu")
		(tenting
			(front yes)
			(back yes)
		)
		(net "GND")
	)
	(via
		(at 172.661105 108.843605)
		(size 0.6)
		(drill 0.3)
		(layers "F.Cu" "B.Cu")
		(tenting
			(front yes)
			(back yes)
		)
		(net "GND")
	)
	(via
		(at 136.661105 129.343605)
		(size 0.6)
		(drill 0.3)
		(layers "F.Cu" "B.Cu")
		(tenting
			(front yes)
			(back yes)
		)
		(net "GND")
	)
	(via
		(at 140.906105 80.703605)
		(size 0.6)
		(drill 0.3)
		(layers "F.Cu" "B.Cu")
		(tenting
			(front yes)
			(back yes)
		)
		(net "GND")
	)
	(via
		(at 172.661105 120.843605)
		(size 0.6)
		(drill 0.3)
		(layers "F.Cu" "B.Cu")
		(tenting
			(front yes)
			(back yes)
		)
		(net "GND")
	)
	(via
		(at 149.276105 113.957705)
		(size 0.6)
		(drill 0.3)
		(layers "F.Cu" "B.Cu")
		(tenting
			(front yes)
			(back yes)
		)
		(net "GND")
	)
	(via
		(at 172.661105 118.843605)
		(size 0.6)
		(drill 0.3)
		(layers "F.Cu" "B.Cu")
		(tenting
			(front yes)
			(back yes)
		)
		(net "GND")
	)
	(via
		(at 140.916105 83.178605)
		(size 0.6)
		(drill 0.3)
		(layers "F.Cu" "B.Cu")
		(tenting
			(front yes)
			(back yes)
		)
		(net "GND")
	)
	(via
		(at 144.661105 129.343605)
		(size 0.6)
		(drill 0.3)
		(layers "F.Cu" "B.Cu")
		(tenting
			(front yes)
			(back yes)
		)
		(net "GND")
	)
	(via
		(at 172.661105 114.843605)
		(size 0.6)
		(drill 0.3)
		(layers "F.Cu" "B.Cu")
		(tenting
			(front yes)
			(back yes)
		)
		(net "GND")
	)
	(via
		(at 125.161105 105.343605)
		(size 0.6)
		(drill 0.3)
		(layers "F.Cu" "B.Cu")
		(tenting
			(front yes)
			(back yes)
		)
		(net "GND")
	)
	(via
		(at 125.161105 109.343605)
		(size 0.6)
		(drill 0.3)
		(layers "F.Cu" "B.Cu")
		(tenting
			(front yes)
			(back yes)
		)
		(net "GND")
	)
	(via
		(at 144.470815 102.303605)
		(size 0.6)
		(drill 0.3)
		(layers "F.Cu" "B.Cu")
		(tenting
			(front yes)
			(back yes)
		)
		(net "GND")
	)
	(via
		(at 156.661105 128.843605)
		(size 0.6)
		(drill 0.3)
		(layers "F.Cu" "B.Cu")
		(tenting
			(front yes)
			(back yes)
		)
		(net "GND")
	)
	(via
		(at 134.661105 129.343605)
		(size 0.6)
		(drill 0.3)
		(layers "F.Cu" "B.Cu")
		(tenting
			(front yes)
			(back yes)
		)
		(net "GND")
	)
	(via
		(at 172.661105 92.843605)
		(size 0.6)
		(drill 0.3)
		(layers "F.Cu" "B.Cu")
		(tenting
			(front yes)
			(back yes)
		)
		(net "GND")
	)
	(via
		(at 167.761105 86.428605)
		(size 0.6)
		(drill 0.3)
		(layers "F.Cu" "B.Cu")
		(tenting
			(front yes)
			(back yes)
		)
		(net "GND")
	)
	(via
		(at 172.661105 90.843605)
		(size 0.6)
		(drill 0.3)
		(layers "F.Cu" "B.Cu")
		(tenting
			(front yes)
			(back yes)
		)
		(net "GND")
	)
	(via
		(at 172.661105 94.843605)
		(size 0.6)
		(drill 0.3)
		(layers "F.Cu" "B.Cu")
		(tenting
			(front yes)
			(back yes)
		)
		(net "GND")
	)
	(segment
		(start 144.476105 107.303605)
		(end 144.505025 107.332525)
		(width 0.2)
		(layer "B.Cu")
		(net "+5V")
	)
	(segment
		(start 144.563605 108.341105)
		(end 144.563605 107.473945)
		(width 0.2)
		(layer "B.Cu")
		(net "+5V")
	)
	(arc
		(start 144.505026 107.332524)
		(mid 144.54838 107.397409)
		(end 144.563604 107.473945)
		(width 0.2)
		(layer "B.Cu")
		(net "+5V")
	)
	(zone
		(net "GND")
		(layer "F.Cu")
		(hatch edge 0.5)
		(connect_pads
			(clearance 0.5)
		)
		(min_thickness 0.25)
		(fill yes
			(thermal_gap 0.254)
			(thermal_bridge_width 0.254)
			(island_removal_mode 0)
		)
		(polygon
			(pts
				(xy 123.101105 127.403605)
				(arc
					(start 123.101095 82.603601)
					(mid 123.979777 80.482282)
					(end 126.101099 79.603605)
				)
				(xy 126.101105 79.603605) (xy 126.001105 79.603595)
				(arc
					(start 170.901105 79.603605)
					(mid 173.022425 80.482285)
					(end 173.901105 82.603605)
				)
				(arc
					(start 173.901105 127.403605)
					(mid 173.022425 129.524925)
					(end 170.901105 130.403605)
				)
				(arc
					(start 126.101102 130.403605)
					(mid 123.979783 129.524923)
					(end 123.101105 127.403602)
				)
			)
		)
	)
	(zone
		(net "+3.3V_OSC")
		(layer "B.Cu")
		(hatch edge 0.5)
		(priority 4)
		(connect_pads
			(clearance 0.5)
		)
		(min_thickness 0.25)
		(fill yes
			(thermal_gap 0.254)
			(thermal_bridge_width 0.254)
			(island_removal_mode 0)
		)
		(polygon
			(pts
				(arc
					(start 162.901095 114.228607)
					(mid 163.025575 113.928084)
					(end 163.326099 113.803605)
				)
				(xy 163.326105 113.803605)
				(arc
					(start 165.926105 113.803605)
					(mid 166.198341 113.916369)
					(end 166.311105 114.188605)
				)
				(arc
					(start 166.311105 115.813605)
					(mid 166.439978 116.124732)
					(end 166.751105 116.253605)
				)
				(arc
					(start 167.25111 116.253605)
					(mid 167.427885 116.326826)
					(end 167.501105 116.5036)
				)
				(xy 167.501105 116.503605)
				(arc
					(start 167.501105 116.928605)
					(mid 167.640229 117.264481)
					(end 167.976105 117.403605)
				)
				(arc
					(start 170.2011 117.403605)
					(mid 170.572329 117.557371)
					(end 170.726095 117.9286)
				)
				(xy 170.726105 117.928605)
				(arc
					(start 170.726105 121.453605)
					(mid 170.499113 122.001613)
					(end 169.951105 122.228605)
				)
				(arc
					(start 163.751098 122.228605)
					(mid 163.150054 121.979645)
					(end 162.901095 121.378601)
				)
				(xy 162.901105 121.378605) (xy 162.901105 114.228605)
			)
		)
	)
	(zone
		(net "+3.3V")
		(layer "B.Cu")
		(hatch edge 0.5)
		(priority 2)
		(connect_pads
			(clearance 0.5)
		)
		(min_thickness 0.25)
		(fill yes
			(thermal_gap 0.254)
			(thermal_bridge_width 0.254)
			(island_removal_mode 0)
		)
		(polygon
			(pts
				(arc
					(start 162.876099 121.354086)
					(mid 162.784027 121.962842)
					(end 162.236092 122.243606)
				)
				(xy 162.236095 122.243605)
				(arc
					(start 152.801105 122.243605)
					(mid 152.040965 121.928745)
					(end 151.726105 121.168605)
				)
				(arc
					(start 151.726105 112.301106)
					(mid 151.816902 112.081902)
					(end 152.036105 111.991105)
				)
				(arc
					(start 152.678605 111.991105)
					(mid 152.95968 111.87468)
					(end 153.076105 111.593605)
				)
				(arc
					(start 153.076105 102.233604)
					(mid 152.808114 101.586597)
					(end 152.161106 101.318605)
				)
				(xy 152.161105 101.318605)
				(arc
					(start 143.711105 101.318605)
					(mid 143.375229 101.457729)
					(end 143.236105 101.793605)
				)
				(xy 143.236105 104.698605)
				(arc
					(start 142.561105 104.698605)
					(mid 142.412613 104.760113)
					(end 142.351105 104.908605)
				)
				(xy 142.351105 106.488605)
				(arc
					(start 140.981105 106.488605)
					(mid 140.878572 106.446139)
					(end 140.836105 106.343605)
				)
				(arc
					(start 140.836105 105.443606)
					(mid 140.928366 105.220867)
					(end 141.151105 105.128605)
				)
				(arc
					(start 141.321102 105.128595)
					(mid 141.646367 104.993867)
					(end 141.781095 104.668602)
				)
				(xy 141.781105 104.668605)
				(arc
					(start 141.781105 101.798604)
					(mid 142.075463 101.087962)
					(end 142.786105 100.793605)
				)
				(arc
					(start 160.336107 100.793605)
					(mid 162.132158 101.537544)
					(end 162.876105 103.333592)
				)
				(xy 162.876095 103.333585) (xy 162.876095 121.354085)
			)
		)
	)
	(zone
		(net "SW")
		(layer "B.Cu")
		(hatch edge 0.5)
		(priority 11)
		(connect_pads
			(clearance 0.5)
		)
		(min_thickness 0.25)
		(fill yes
			(thermal_gap 0.254)
			(thermal_bridge_width 0.254)
			(island_removal_mode 0)
		)
		(polygon
			(pts
				(xy 146.276105 107.453605) (xy 146.704755 107.453595) (xy 147.476105 108.224945) (xy 147.476105 110.987315)
				(xy 147.942395 111.453605) (xy 150.076105 111.453605) (xy 150.076105 105.153605) (xy 147.376105 105.153605)
				(xy 147.201105 105.328605) (xy 147.201105 106.703585) (xy 146.751105 107.153605) (xy 146.276105 107.153605)
			)
		)
	)
	(zone
		(layer "B.Cu")
		(hatch edge 0.5)
		(connect_pads
			(clearance 0)
		)
		(min_thickness 0.25)
		(keepout
			(tracks allowed)
			(vias allowed)
			(pads allowed)
			(copperpour not_allowed)
			(footprints allowed)
		)
		(placement
			(enabled no)
			(sheetname "")
		)
		(fill
			(thermal_gap 0.5)
			(thermal_bridge_width 0.5)
			(island_removal_mode 0)
		)
		(polygon
			(pts
				(xy 150.076105 105.653605) (xy 153.076105 105.653605) (xy 153.076105 111.453605) (xy 150.076105 111.453605)
			)
		)
	)
	(zone
		(layer "B.Cu")
		(hatch edge 0.5)
		(connect_pads
			(clearance 0)
		)
		(min_thickness 0.25)
		(keepout
			(tracks allowed)
			(vias allowed)
			(pads allowed)
			(copperpour not_allowed)
			(footprints allowed)
		)
		(placement
			(enabled no)
			(sheetname "")
		)
		(fill
			(thermal_gap 0.5)
			(thermal_bridge_width 0.5)
			(island_removal_mode 0)
		)
		(polygon
			(pts
				(xy 145.676105 108.353605) (xy 145.676105 107.628605) (xy 146.076105 107.628605) (xy 146.076105 107.453605)
				(xy 145.476105 107.453605) (xy 145.476105 108.353605)
			)
		)
	)
	(zone
		(net "GND")
		(layer "B.Cu")
		(hatch edge 0.5)
		(priority 1)
		(connect_pads
			(clearance 0.5)
		)
		(min_thickness 0.25)
		(fill yes
			(thermal_gap 0.254)
			(thermal_bridge_width 0.254)
			(island_removal_mode 0)
		)
		(polygon
			(pts
				(xy 123.101105 127.403605)
				(arc
					(start 123.101095 82.603601)
					(mid 123.979777 80.482282)
					(end 126.101099 79.603605)
				)
				(xy 126.101105 79.603605) (xy 126.001105 79.603595)
				(arc
					(start 170.901105 79.603605)
					(mid 173.022425 80.482285)
					(end 173.901105 82.603605)
				)
				(arc
					(start 173.901105 127.403605)
					(mid 173.022425 129.524925)
					(end 170.901105 130.403605)
				)
				(arc
					(start 126.101102 130.403605)
					(mid 123.979783 129.524923)
					(end 123.101105 127.403602)
				)
			)
		)
	)
	(zone
		(layer "B.Cu")
		(hatch edge 0.5)
		(connect_pads
			(clearance 0)
		)
		(min_thickness 0.25)
		(keepout
			(tracks allowed)
			(vias allowed)
			(pads allowed)
			(copperpour not_allowed)
			(footprints allowed)
		)
		(placement
			(enabled no)
			(sheetname "")
		)
		(fill
			(thermal_gap 0.5)
			(thermal_bridge_width 0.5)
			(island_removal_mode 0)
		)
		(polygon
			(pts
				(xy 145.426105 103.883605) (xy 145.426105 104.168605) (xy 146.081105 104.168605) (xy 146.081105 103.858605)
			)
		)
	)
	(zone
		(net "+5V")
		(layer "B.Cu")
		(hatch edge 0.5)
		(priority 3)
		(connect_pads
			(clearance 0.5)
		)
		(min_thickness 0.25)
		(fill yes
			(thermal_gap 0.254)
			(thermal_bridge_width 0.254)
			(island_removal_mode 0)
		)
		(polygon
			(pts
				(arc
					(start 124.486105 112.508605)
					(mid 125.230052 110.712559)
					(end 127.026099 109.968615)
				)
				(xy 127.026105 109.968605)
				(arc
					(start 143.494855 109.968605)
					(mid 143.722013 109.874513)
					(end 143.816105 109.647355)
				)
				(arc
					(start 143.816105 107.988607)
					(mid 143.921546 107.734051)
					(end 144.176103 107.628615)
				)
				(xy 144.176105 107.628605) (xy 144.976105 107.628605)
				(arc
					(start 144.976105 109.91361)
					(mid 145.017107 110.012603)
					(end 145.116099 110.053605)
				)
				(xy 145.116105 110.053605)
				(arc
					(start 145.116105 111.313608)
					(mid 145.075101 111.412605)
					(end 144.976102 111.453605)
				)
				(arc
					(start 144.976105 111.453605)
					(mid 144.799328 111.526828)
					(end 144.726105 111.703605)
				)
				(arc
					(start 144.726105 127.453605)
					(mid 144.384884 128.277384)
					(end 143.561105 128.618605)
				)
				(arc
					(start 125.736098 128.618605)
					(mid 124.852208 128.252493)
					(end 124.486105 127.368599)
				)
				(xy 124.486105 127.368595)
			)
		)
	)
	(zone
		(layer "B.Cu")
		(hatch edge 0.5)
		(connect_pads
			(clearance 0)
		)
		(min_thickness 0.25)
		(keepout
			(tracks not_allowed)
			(vias not_allowed)
			(pads not_allowed)
			(copperpour not_allowed)
			(footprints allowed)
		)
		(placement
			(enabled no)
			(sheetname "")
		)
		(fill
			(thermal_gap 0.5)
			(thermal_bridge_width 0.5)
			(island_removal_mode 0)
		)
		(polygon
			(pts
				(xy 125.801105 101.028605) (xy 125.801105 108.903605) (xy 131.126105 108.903605) (xy 131.126105 101.028605)
			)
		)
	)
	(zone
		(net "GND")
		(layer "In1.Cu")
		(hatch edge 0.5)
		(priority 18)
		(connect_pads
			(clearance 0.5)
		)
		(min_thickness 0.25)
		(fill yes
			(thermal_gap 0.254)
			(thermal_bridge_width 0.254)
			(island_removal_mode 0)
		)
		(polygon
			(pts
				(xy 123.101105 127.403605)
				(arc
					(start 123.101095 82.603601)
					(mid 123.979777 80.482282)
					(end 126.101099 79.603605)
				)
				(xy 126.101105 79.603605) (xy 126.001105 79.603595)
				(arc
					(start 170.901105 79.603605)
					(mid 173.022425 80.482285)
					(end 173.901105 82.603605)
				)
				(arc
					(start 173.901105 127.403605)
					(mid 173.022425 129.524925)
					(end 170.901105 130.403605)
				)
				(arc
					(start 126.101102 130.403605)
					(mid 123.979783 129.524923)
					(end 123.101105 127.403602)
				)
			)
		)
	)
	(zone
		(net "GND")
		(layer "In2.Cu")
		(hatch edge 0.5)
		(priority 20)
		(connect_pads
			(clearance 0.5)
		)
		(min_thickness 0.25)
		(fill yes
			(thermal_gap 0.254)
			(thermal_bridge_width 0.254)
			(island_removal_mode 0)
		)
		(polygon
			(pts
				(xy 123.101105 127.403605)
				(arc
					(start 123.101095 82.603601)
					(mid 123.979777 80.482282)
					(end 126.101099 79.603605)
				)
				(xy 126.101105 79.603605) (xy 126.001105 79.603595)
				(arc
					(start 170.901105 79.603605)
					(mid 173.022425 80.482285)
					(end 173.901105 82.603605)
				)
				(arc
					(start 173.901105 127.403605)
					(mid 173.022425 129.524925)
					(end 170.901105 130.403605)
				)
				(arc
					(start 126.101102 130.403605)
					(mid 123.979783 129.524923)
					(end 123.101105 127.403602)
				)
			)
		)
	)
)
